G04 ================== begin FILE IDENTIFICATION RECORD ==================*
G04 Layout Name:  13948-1b.brd*
G04 Film Name:    L7GND*
G04 File Format:  Gerber RS274X*
G04 File Origin:  Cadence Allegro 16.5-S045*
G04 Origin Date:  Thu Nov 13 15:46:18 2014*
G04 *
G04 Layer:  VIA CLASS/L7GND*
G04 Layer:  PIN/L7GND*
G04 Layer:  ETCH/L7GND*
G04 Layer:  DRAWING FORMAT/LAYER_PCB_STORY*
G04 Layer:  DRAWING FORMAT/LAYER_L7GND*
G04 *
G04 Offset:    (0.00 0.00)*
G04 Mirror:    No*
G04 Mode:      Negative*
G04 Rotation:  0*
G04 FullContactRelief:  No*
G04 UndefLineWidth:     6.00*
G04 ================== end FILE IDENTIFICATION RECORD ====================*
%FSLAX35Y35*MOIN*%
%IR0*IPPOS*OFA0.00000B0.00000*MIA0B0*SFA1.00000B1.00000*%
%ADD17C,.03*%
%ADD13C,.032*%
%ADD47C,.06*%
%ADD43C,.07*%
%ADD42C,.062*%
%ADD19C,.036*%
%ADD18C,.063*%
%ADD12C,.09*%
%ADD36C,.064*%
%ADD22C,.073*%
%ADD39C,.066*%
%ADD31C,.057*%
%ADD41C,.076*%
%ADD28C,.059*%
%ADD24C,.068*%
%ADD33C,.078*%
%ADD15C,.089*%
%AMMACRO44*
4,1,14,.02707,.01293,
.028904,.008033,
.02986,.002892,
.029908,-.002337,
.029048,-.007495,
.027305,-.012426,
.02707,-.01293,
.03079,-.01665,
.033213,-.01105,
.034628,-.005115,
.03499,.000976,
.034289,.007037,
.032546,.012884,
.03079,.01665,
.02707,.01293,
270.*
4,1,14,.01293,-.02707,
.008033,-.028904,
.002892,-.02986,
-.002337,-.029908,
-.007495,-.029048,
-.012426,-.027305,
-.01293,-.02707,
-.01665,-.03079,
-.01105,-.033213,
-.005115,-.034628,
.000976,-.03499,
.007037,-.034289,
.012884,-.032546,
.01665,-.03079,
.01293,-.02707,
270.*
4,1,14,-.02707,-.01293,
-.028904,-.008033,
-.02986,-.002892,
-.029908,.002337,
-.029048,.007495,
-.027305,.012426,
-.02707,.01293,
-.03079,.01665,
-.033213,.01105,
-.034628,.005115,
-.03499,-.000976,
-.034289,-.007037,
-.032546,-.012884,
-.03079,-.01665,
-.02707,-.01293,
270.*
4,1,14,-.01293,.02707,
-.008033,.028904,
-.002892,.02986,
.002337,.029908,
.007495,.029048,
.012426,.027305,
.01293,.02707,
.01665,.03079,
.01105,.033213,
.005115,.034628,
-.000976,.03499,
-.007037,.034289,
-.012884,.032546,
-.01665,.03079,
-.01293,.02707,
270.*
%
%ADD44MACRO44*%
%AMMACRO29*
4,1,15,.00398,.00044,
.003999,.000208,
.004004,-.000025,
.003996,-.000258,
.00398,-.00044,
.00483,-.00129,
.004897,-.001007,
.004947,-.000721,
.004981,-.000432,
.004997,-.000141,
.004997,.000149,
.00498,.00044,
.004946,.000729,
.004895,.001015,
.00483,.00129,
.00398,.00044,
90.*
4,1,15,.00044,-.00398,
.000208,-.003999,
-.000025,-.004004,
-.000258,-.003996,
-.00044,-.00398,
-.00129,-.00483,
-.001007,-.004897,
-.000721,-.004947,
-.000432,-.004981,
-.000141,-.004997,
.000149,-.004997,
.00044,-.00498,
.000729,-.004946,
.001015,-.004895,
.00129,-.00483,
.00044,-.00398,
90.*
4,1,15,-.00398,-.00044,
-.003999,-.000208,
-.004004,.000025,
-.003996,.000258,
-.00398,.00044,
-.00483,.00129,
-.004897,.001007,
-.004947,.000721,
-.004981,.000432,
-.004997,.000141,
-.004997,-.000149,
-.00498,-.00044,
-.004946,-.000729,
-.004895,-.001015,
-.00483,-.00129,
-.00398,-.00044,
90.*
4,1,15,-.00044,.00398,
-.000208,.003999,
.000025,.004004,
.000258,.003996,
.00044,.00398,
.00129,.00483,
.001007,.004897,
.000721,.004947,
.000432,.004981,
.000141,.004997,
-.000149,.004997,
-.00044,.00498,
-.000729,.004946,
-.001015,.004895,
-.00129,.00483,
-.00044,.00398,
90.*
%
%ADD29MACRO29*%
%AMMACRO10*
4,1,15,.00398,.00044,
.003999,.000208,
.004004,-.000025,
.003996,-.000258,
.00398,-.00044,
.00483,-.00129,
.004897,-.001007,
.004947,-.000721,
.004981,-.000432,
.004997,-.000141,
.004997,.000149,
.00498,.00044,
.004946,.000729,
.004895,.001015,
.00483,.00129,
.00398,.00044,
0.0*
4,1,15,.00044,-.00398,
.000208,-.003999,
-.000025,-.004004,
-.000258,-.003996,
-.00044,-.00398,
-.00129,-.00483,
-.001007,-.004897,
-.000721,-.004947,
-.000432,-.004981,
-.000141,-.004997,
.000149,-.004997,
.00044,-.00498,
.000729,-.004946,
.001015,-.004895,
.00129,-.00483,
.00044,-.00398,
0.0*
4,1,15,-.00398,-.00044,
-.003999,-.000208,
-.004004,.000025,
-.003996,.000258,
-.00398,.00044,
-.00483,.00129,
-.004897,.001007,
-.004947,.000721,
-.004981,.000432,
-.004997,.000141,
-.004997,-.000149,
-.00498,-.00044,
-.004946,-.000729,
-.004895,-.001015,
-.00483,-.00129,
-.00398,-.00044,
0.0*
4,1,15,-.00044,.00398,
-.000208,.003999,
.000025,.004004,
.000258,.003996,
.00044,.00398,
.00129,.00483,
.001007,.004897,
.000721,.004947,
.000432,.004981,
.000141,.004997,
-.000149,.004997,
-.00044,.00498,
-.000729,.004946,
-.001015,.004895,
-.00129,.00483,
-.00044,.00398,
0.0*
%
%ADD10MACRO10*%
%AMMACRO45*
4,1,13,.02442,.01028,
.025834,.005883,
.026463,.001308,
.026288,-.003307,
.025315,-.007822,
.02442,-.01028,
.02819,-.01405,
.030201,-.008941,
.031295,-.003561,
.031438,.001927,
.030626,.007357,
.028883,.012564,
.02819,.01405,
.02442,.01028,
180.*
4,1,13,.01028,-.02442,
.005883,-.025834,
.001308,-.026463,
-.003307,-.026288,
-.007822,-.025315,
-.01028,-.02442,
-.01405,-.02819,
-.008941,-.030201,
-.003561,-.031295,
.001927,-.031438,
.007357,-.030626,
.012564,-.028883,
.01405,-.02819,
.01028,-.02442,
180.*
4,1,13,-.02442,-.01028,
-.025834,-.005883,
-.026463,-.001308,
-.026288,.003307,
-.025315,.007822,
-.02442,.01028,
-.02819,.01405,
-.030201,.008941,
-.031295,.003561,
-.031438,-.001927,
-.030626,-.007357,
-.028883,-.012564,
-.02819,-.01405,
-.02442,-.01028,
180.*
4,1,13,-.01028,.02442,
-.005883,.025834,
-.001308,.026463,
.003307,.026288,
.007822,.025315,
.01028,.02442,
.01405,.02819,
.008941,.030201,
.003561,.031295,
-.001927,.031438,
-.007357,.030626,
-.012564,.028883,
-.01405,.02819,
-.01028,.02442,
180.*
%
%ADD45MACRO45*%
%AMMACRO32*
4,1,19,.02211,.00797,
.022536,.006671,
.022886,.005349,
.023158,.00401,
.023352,.002656,
.023467,.001294,
.023503,-.000073,
.023459,-.001439,
.023335,-.002801,
.023133,-.004153,
.022852,-.005491,
.022494,-.00681,
.02211,-.00797,
.02594,-.0118,
.027595,-.007116,
.028411,-.002216,
.028365,.002751,
.027456,.007635,
.02594,.0118,
.02211,.00797,
180.*
4,1,19,.00797,-.02211,
.006671,-.022536,
.005349,-.022886,
.00401,-.023158,
.002656,-.023352,
.001294,-.023467,
-.000073,-.023503,
-.001439,-.023459,
-.002801,-.023335,
-.004153,-.023133,
-.005491,-.022852,
-.00681,-.022494,
-.00797,-.02211,
-.0118,-.02594,
-.007116,-.027595,
-.002216,-.028411,
.002751,-.028365,
.007635,-.027456,
.0118,-.02594,
.00797,-.02211,
180.*
4,1,19,-.02211,-.00797,
-.022536,-.006671,
-.022886,-.005349,
-.023158,-.00401,
-.023352,-.002656,
-.023467,-.001294,
-.023503,.000073,
-.023459,.001439,
-.023335,.002801,
-.023133,.004153,
-.022852,.005491,
-.022494,.00681,
-.02211,.00797,
-.02594,.0118,
-.027595,.007116,
-.028411,.002216,
-.028365,-.002751,
-.027456,-.007635,
-.02594,-.0118,
-.02211,-.00797,
180.*
4,1,19,-.00797,.02211,
-.006671,.022536,
-.005349,.022886,
-.00401,.023158,
-.002656,.023352,
-.001294,.023467,
.000073,.023503,
.001439,.023459,
.002801,.023335,
.004153,.023133,
.005491,.022852,
.00681,.022494,
.00797,.02211,
.0118,.02594,
.007116,.027595,
.002216,.028411,
-.002751,.028365,
-.007635,.027456,
-.0118,.02594,
-.00797,.02211,
180.*
%
%ADD32MACRO32*%
%AMMACRO46*
4,1,13,.02632,.01218,
.028035,.007425,
.028899,.002443,
.028884,-.002612,
.027991,-.007588,
.02632,-.01218,
.03005,-.01591,
.032356,-.01045,
.033679,-.004673,
.033979,.001247,
.033246,.007128,
.031504,.012793,
.03005,.01591,
.02632,.01218,
180.*
4,1,13,.01218,-.02632,
.007425,-.028035,
.002443,-.028899,
-.002612,-.028884,
-.007588,-.027991,
-.01218,-.02632,
-.01591,-.03005,
-.01045,-.032356,
-.004673,-.033679,
.001247,-.033979,
.007128,-.033246,
.012793,-.031504,
.01591,-.03005,
.01218,-.02632,
180.*
4,1,13,-.02632,-.01218,
-.028035,-.007425,
-.028899,-.002443,
-.028884,.002612,
-.027991,.007588,
-.02632,.01218,
-.03005,.01591,
-.032356,.01045,
-.033679,.004673,
-.033979,-.001247,
-.033246,-.007128,
-.031504,-.012793,
-.03005,-.01591,
-.02632,-.01218,
180.*
4,1,13,-.01218,.02632,
-.007425,.028035,
-.002443,.028899,
.002612,.028884,
.007588,.027991,
.01218,.02632,
.01591,.03005,
.01045,.032356,
.004673,.033679,
-.001247,.033979,
-.007128,.033246,
-.012793,.031504,
-.01591,.03005,
-.01218,.02632,
180.*
%
%ADD46MACRO46*%
%AMMACRO23*
4,1,13,.02632,.01218,
.028035,.007425,
.028899,.002443,
.028884,-.002612,
.027991,-.007588,
.02632,-.01218,
.03005,-.01591,
.032356,-.01045,
.033679,-.004673,
.033979,.001247,
.033246,.007128,
.031504,.012793,
.03005,.01591,
.02632,.01218,
270.*
4,1,13,.01218,-.02632,
.007425,-.028035,
.002443,-.028899,
-.002612,-.028884,
-.007588,-.027991,
-.01218,-.02632,
-.01591,-.03005,
-.01045,-.032356,
-.004673,-.033679,
.001247,-.033979,
.007128,-.033246,
.012793,-.031504,
.01591,-.03005,
.01218,-.02632,
270.*
4,1,13,-.02632,-.01218,
-.028035,-.007425,
-.028899,-.002443,
-.028884,.002612,
-.027991,.007588,
-.02632,.01218,
-.03005,.01591,
-.032356,.01045,
-.033679,.004673,
-.033979,-.001247,
-.033246,-.007128,
-.031504,-.012793,
-.03005,-.01591,
-.02632,-.01218,
270.*
4,1,13,-.01218,.02632,
-.007425,.028035,
-.002443,.028899,
.002612,.028884,
.007588,.027991,
.01218,.02632,
.01591,.03005,
.01045,.032356,
.004673,.033679,
-.001247,.033979,
-.007128,.033246,
-.012793,.031504,
-.01591,.03005,
-.01218,.02632,
270.*
%
%ADD23MACRO23*%
%ADD37O,.217X.154*%
%ADD30C,.121*%
%ADD14C,.114*%
%ADD26C,.154*%
%ADD38C,.119*%
%ADD35C,.156*%
%ADD27C,.166*%
%AMMACRO20*
4,1,15,.00398,.00044,
.003999,.000208,
.004004,-.000025,
.003996,-.000258,
.00398,-.00044,
.00483,-.00129,
.004897,-.001007,
.004947,-.000721,
.004981,-.000432,
.004997,-.000141,
.004997,.000149,
.00498,.00044,
.004946,.000729,
.004895,.001015,
.00483,.00129,
.00398,.00044,
180.*
4,1,15,.00044,-.00398,
.000208,-.003999,
-.000025,-.004004,
-.000258,-.003996,
-.00044,-.00398,
-.00129,-.00483,
-.001007,-.004897,
-.000721,-.004947,
-.000432,-.004981,
-.000141,-.004997,
.000149,-.004997,
.00044,-.00498,
.000729,-.004946,
.001015,-.004895,
.00129,-.00483,
.00044,-.00398,
180.*
4,1,15,-.00398,-.00044,
-.003999,-.000208,
-.004004,.000025,
-.003996,.000258,
-.00398,.00044,
-.00483,.00129,
-.004897,.001007,
-.004947,.000721,
-.004981,.000432,
-.004997,.000141,
-.004997,-.000149,
-.00498,-.00044,
-.004946,-.000729,
-.004895,-.001015,
-.00483,-.00129,
-.00398,-.00044,
180.*
4,1,15,-.00044,.00398,
-.000208,.003999,
.000025,.004004,
.000258,.003996,
.00044,.00398,
.00129,.00483,
.001007,.004897,
.000721,.004947,
.000432,.004981,
.000141,.004997,
-.000149,.004997,
-.00044,.00498,
-.000729,.004946,
-.001015,.004895,
-.00129,.00483,
-.00044,.00398,
180.*
%
%ADD20MACRO20*%
%AMMACRO16*
4,1,15,.00398,.00044,
.003999,.000208,
.004004,-.000025,
.003996,-.000258,
.00398,-.00044,
.00483,-.00129,
.004897,-.001007,
.004947,-.000721,
.004981,-.000432,
.004997,-.000141,
.004997,.000149,
.00498,.00044,
.004946,.000729,
.004895,.001015,
.00483,.00129,
.00398,.00044,
270.*
4,1,15,.00044,-.00398,
.000208,-.003999,
-.000025,-.004004,
-.000258,-.003996,
-.00044,-.00398,
-.00129,-.00483,
-.001007,-.004897,
-.000721,-.004947,
-.000432,-.004981,
-.000141,-.004997,
.000149,-.004997,
.00044,-.00498,
.000729,-.004946,
.001015,-.004895,
.00129,-.00483,
.00044,-.00398,
270.*
4,1,15,-.00398,-.00044,
-.003999,-.000208,
-.004004,.000025,
-.003996,.000258,
-.00398,.00044,
-.00483,.00129,
-.004897,.001007,
-.004947,.000721,
-.004981,.000432,
-.004997,.000141,
-.004997,-.000149,
-.00498,-.00044,
-.004946,-.000729,
-.004895,-.001015,
-.00483,-.00129,
-.00398,-.00044,
270.*
4,1,15,-.00044,.00398,
-.000208,.003999,
.000025,.004004,
.000258,.003996,
.00044,.00398,
.00129,.00483,
.001007,.004897,
.000721,.004947,
.000432,.004981,
.000141,.004997,
-.000149,.004997,
-.00044,.00498,
-.000729,.004946,
-.001015,.004895,
-.00129,.00483,
-.00044,.00398,
270.*
%
%ADD16MACRO16*%
%AMMACRO21*
4,1,13,.02327,.00913,
.024502,.004951,
.024989,.000621,
.024717,-.003728,
.023695,-.007964,
.02327,-.00913,
.02707,-.01293,
.028904,-.008033,
.02986,-.002892,
.029908,.002337,
.029048,.007495,
.027305,.012426,
.02707,.01293,
.02327,.00913,
0.0*
4,1,13,.00913,-.02327,
.004951,-.024502,
.000621,-.024989,
-.003728,-.024717,
-.007964,-.023695,
-.00913,-.02327,
-.01293,-.02707,
-.008033,-.028904,
-.002892,-.02986,
.002337,-.029908,
.007495,-.029048,
.012426,-.027305,
.01293,-.02707,
.00913,-.02327,
0.0*
4,1,13,-.02327,-.00913,
-.024502,-.004951,
-.024989,-.000621,
-.024717,.003728,
-.023695,.007964,
-.02327,.00913,
-.02707,.01293,
-.028904,.008033,
-.02986,.002892,
-.029908,-.002337,
-.029048,-.007495,
-.027305,-.012426,
-.02707,-.01293,
-.02327,-.00913,
0.0*
4,1,13,-.00913,.02327,
-.004951,.024502,
-.000621,.024989,
.003728,.024717,
.007964,.023695,
.00913,.02327,
.01293,.02707,
.008033,.028904,
.002892,.02986,
-.002337,.029908,
-.007495,.029048,
-.012426,.027305,
-.01293,.02707,
-.00913,.02327,
0.0*
%
%ADD21MACRO21*%
%AMMACRO34*
4,1,13,.03683,.01561,
.038981,.008977,
.039948,.002072,
.039701,-.004896,
.038247,-.011716,
.03683,-.01561,
.04061,-.01939,
.04336,-.012044,
.044793,-.004331,
.044864,.003513,
.043573,.01125,
.040957,.018645,
.04061,.01939,
.03683,.01561,
0.0*
4,1,13,.01561,-.03683,
.008977,-.038981,
.002072,-.039948,
-.004896,-.039701,
-.011716,-.038247,
-.01561,-.03683,
-.01939,-.04061,
-.012044,-.04336,
-.004331,-.044793,
.003513,-.044864,
.01125,-.043573,
.018645,-.040957,
.01939,-.04061,
.01561,-.03683,
0.0*
4,1,13,-.03683,-.01561,
-.038981,-.008977,
-.039948,-.002072,
-.039701,.004896,
-.038247,.011716,
-.03683,.01561,
-.04061,.01939,
-.04336,.012044,
-.044793,.004331,
-.044864,-.003513,
-.043573,-.01125,
-.040957,-.018645,
-.04061,-.01939,
-.03683,-.01561,
0.0*
4,1,13,-.01561,.03683,
-.008977,.038981,
-.002072,.039948,
.004896,.039701,
.011716,.038247,
.01561,.03683,
.01939,.04061,
.012044,.04336,
.004331,.044793,
-.003513,.044864,
-.01125,.043573,
-.018645,.040957,
-.01939,.04061,
-.01561,.03683,
0.0*
%
%ADD34MACRO34*%
%AMMACRO25*
4,1,14,.02819,.01405,
.030201,.008941,
.031295,.003561,
.031438,-.001927,
.030626,-.007357,
.028883,-.012564,
.02819,-.01405,
.03189,-.01775,
.034488,-.011943,
.036038,-.005773,
.036493,.000573,
.035839,.006901,
.034096,.01302,
.03189,.01775,
.02819,.01405,
0.0*
4,1,14,.01405,-.02819,
.008941,-.030201,
.003561,-.031295,
-.001927,-.031438,
-.007357,-.030626,
-.012564,-.028883,
-.01405,-.02819,
-.01775,-.03189,
-.011943,-.034488,
-.005773,-.036038,
.000573,-.036493,
.006901,-.035839,
.01302,-.034096,
.01775,-.03189,
.01405,-.02819,
0.0*
4,1,14,-.02819,-.01405,
-.030201,-.008941,
-.031295,-.003561,
-.031438,.001927,
-.030626,.007357,
-.028883,.012564,
-.02819,.01405,
-.03189,.01775,
-.034488,.011943,
-.036038,.005773,
-.036493,-.000573,
-.035839,-.006901,
-.034096,-.01302,
-.03189,-.01775,
-.02819,-.01405,
0.0*
4,1,14,-.01405,.02819,
-.008941,.030201,
-.003561,.031295,
.001927,.031438,
.007357,.030626,
.012564,.028883,
.01405,.02819,
.01775,.03189,
.011943,.034488,
.005773,.036038,
-.000573,.036493,
-.006901,.035839,
-.01302,.034096,
-.01775,.03189,
-.01405,.02819,
0.0*
%
%ADD25MACRO25*%
%AMMACRO11*
4,1,14,.0575,.02922,
.0617,.018791,
.064026,.007792,
.064406,-.003445,
.06283,-.014576,
.059344,-.025265,
.0575,-.02922,
.06121,-.03292,
.065997,-.021791,
.068778,-.01,
.069469,.002095,
.06805,.014127,
.064563,.025729,
.06121,.03292,
.0575,.02922,
90.*
4,1,14,.02922,-.0575,
.018791,-.0617,
.007792,-.064026,
-.003445,-.064406,
-.014576,-.06283,
-.025265,-.059344,
-.02922,-.0575,
-.03292,-.06121,
-.021791,-.065997,
-.01,-.068778,
.002095,-.069469,
.014127,-.06805,
.025729,-.064563,
.03292,-.06121,
.02922,-.0575,
90.*
4,1,14,-.0575,-.02922,
-.0617,-.018791,
-.064026,-.007792,
-.064406,.003445,
-.06283,.014576,
-.059344,.025265,
-.0575,.02922,
-.06121,.03292,
-.065997,.021791,
-.068778,.01,
-.069469,-.002095,
-.06805,-.014127,
-.064563,-.025729,
-.06121,-.03292,
-.0575,-.02922,
90.*
4,1,14,-.02922,.0575,
-.018791,.0617,
-.007792,.064026,
.003445,.064406,
.014576,.06283,
.025265,.059344,
.02922,.0575,
.03292,.06121,
.021791,.065997,
.01,.068778,
-.002095,.069469,
-.014127,.06805,
-.025729,.064563,
-.03292,.06121,
-.02922,.0575,
90.*
%
%ADD11MACRO11*%
%AMMACRO40*
4,1,13,.02556,.01142,
.027155,.006808,
.027924,.001989,
.027846,-.00289,
.026921,-.007681,
.02556,-.01142,
.02931,-.01517,
.031499,-.00985,
.032731,-.004231,
.032968,.001517,
.032204,.007219,
.030461,.012702,
.02931,.01517,
.02556,.01142,
0.0*
4,1,13,.01142,-.02556,
.006808,-.027155,
.001989,-.027924,
-.00289,-.027846,
-.007681,-.026921,
-.01142,-.02556,
-.01517,-.02931,
-.00985,-.031499,
-.004231,-.032731,
.001517,-.032968,
.007219,-.032204,
.012702,-.030461,
.01517,-.02931,
.01142,-.02556,
0.0*
4,1,13,-.02556,-.01142,
-.027155,-.006808,
-.027924,-.001989,
-.027846,.00289,
-.026921,.007681,
-.02556,.01142,
-.02931,.01517,
-.031499,.00985,
-.032731,.004231,
-.032968,-.001517,
-.032204,-.007219,
-.030461,-.012702,
-.02931,-.01517,
-.02556,-.01142,
0.0*
4,1,13,-.01142,.02556,
-.006808,.027155,
-.001989,.027924,
.00289,.027846,
.007681,.026921,
.01142,.02556,
.01517,.02931,
.00985,.031499,
.004231,.032731,
-.001517,.032968,
-.007219,.032204,
-.012702,.030461,
-.01517,.02931,
-.01142,.02556,
0.0*
%
%ADD40MACRO40*%
%ADD48C,.02*%
%ADD49C,.006*%
%ADD61C,.06204*%
%ADD59C,.07204*%
%ADD58C,.06404*%
%ADD62C,.05604*%
%ADD60C,.05804*%
%ADD53C,.08504*%
%ADD52C,.08604*%
%ADD63C,.06904*%
%ADD50O,.21302X.15002*%
%ADD51O,.21304X.15004*%
%ADD54C,.15004*%
%ADD57C,.15204*%
%ADD56C,.11704*%
%ADD55C,.16204*%
G75*
%LPD*%
G75*
G36*
G01X-6000Y-6000D02*
X1406000D01*
Y1029622D01*
X-6000D01*
Y-6000D01*
G37*
%LPC*%
G75*
G36*
G01X1380315Y985185D02*
G02X1396996Y968504I0J-16681D01*
G01Y3937D01*
G02X1396063Y3004I-933J0D01*
G01X1210571D01*
G02X1209638Y3937I0J933D01*
G01Y171261D01*
G03X1209634Y171487I-6941J-10D01*
G01Y172503D01*
X1209500Y172637D01*
X1209488Y172695D01*
G03X1202697Y178201I-6791J-1435D01*
G02X1201764Y179134I0J933D01*
G01Y210631D01*
G03X1201760Y210857I-6941J-10D01*
G01Y211873D01*
X1201626Y212007D01*
X1201614Y212065D01*
G03X1196258Y217421I-6791J-1435D01*
G01X1196200Y217433D01*
X1196066Y217567D01*
X1195050D01*
G03X1194824Y217571I-236J-6937D01*
G01X1116082D01*
G03X1115856Y217567I10J-6941D01*
G01X1114840D01*
X1114707Y217433D01*
X1114649Y217421D01*
G03X1109292Y212064I1434J-6791D01*
G01X1109280Y212006D01*
X1109146Y211873D01*
Y210857D01*
G03X1109142Y210631I6937J-236D01*
G01Y3937D01*
G02X1108209Y3004I-933J0D01*
G01X297047D01*
G02X296114Y3937I0J933D01*
G01Y62993D01*
G03X296110Y63219I-6941J-10D01*
G01Y64235D01*
X295976Y64368D01*
X295964Y64426D01*
G03X290607Y69783I-6791J-1434D01*
G01X290549Y69795D01*
X290416Y69929D01*
X289400D01*
G03X289174Y69933I-236J-6937D01*
G01X247835D01*
G02X246902Y70866I0J933D01*
G01Y224449D01*
G03X246898Y224675I-6941J-10D01*
G01Y225692D01*
X246764Y225826D01*
X246752Y225884D01*
G03X241396Y231240I-6791J-1435D01*
G01X241338Y231252D01*
X241204Y231386D01*
X240187D01*
G03X239961Y231390I-236J-6937D01*
G01X116142D01*
G02X111272Y236260I0J4870D01*
G01Y299252D01*
G03X111268Y299538I-10878J-9D01*
G01Y300495D01*
X111193Y300570D01*
X111184Y300638D01*
G03X101780Y310042I-10790J-1386D01*
G01X101712Y310051D01*
X101637Y310126D01*
X100680D01*
G03X100394Y310130I-295J-10874D01*
G01X11811D01*
G02X3004Y318937I0J8807D01*
G01Y968504D01*
G02X19685Y985185I16681J0D01*
G01X103741D01*
G03X103967Y985189I-10J6941D01*
G01X104983D01*
X105116Y985323D01*
X105174Y985335D01*
G03X110531Y990692I-1434J6791D01*
G01X110543Y990750D01*
X110677Y990883D01*
Y991899D01*
G03X110681Y992125I-6937J236D01*
G01Y1015106D01*
X133020D01*
Y994291D01*
G03X133024Y994068I6744J9D01*
G01Y993048D01*
X133162Y992910D01*
X133175Y992852D01*
Y992851D01*
G03X146353I6589J1440D01*
G01Y992852D01*
X146366Y992910D01*
X146504Y993048D01*
Y994068D01*
G03X146508Y994291I-6740J232D01*
G01Y1015106D01*
X184594D01*
Y992126D01*
G03X184598Y991900I6941J10D01*
G01Y990883D01*
X184732Y990749D01*
X184744Y990691D01*
G03X190100Y985335I6791J1435D01*
G01X190158Y985323D01*
X190292Y985189D01*
X191309D01*
G03X191535Y985185I236J6937D01*
G01X261221D01*
G03X261447Y985189I-10J6941D01*
G01X262463D01*
X262596Y985323D01*
X262654Y985335D01*
G03X268011Y990692I-1434J6791D01*
G01X268023Y990750D01*
X268157Y990883D01*
Y991899D01*
G03X268161Y992125I-6937J236D01*
G01Y1001600D01*
X542468D01*
Y994291D01*
G03X542472Y994068I6744J9D01*
G01Y993048D01*
X542610Y992910D01*
X542623Y992852D01*
Y992851D01*
G03X555802I6590J1440D01*
G01Y992852D01*
X555815Y992910D01*
X555953Y993048D01*
Y994068D01*
G03X555957Y994291I-6740J232D01*
G01Y1001600D01*
X594043D01*
Y992125D01*
G03X594047Y991899I6941J10D01*
G01Y990883D01*
X594181Y990749D01*
X594193Y990691D01*
G03X599549Y985335I6791J1435D01*
G01X599607Y985323D01*
X599741Y985189D01*
X600757D01*
G03X600983Y985185I236J6937D01*
G01X713190D01*
G03X713416Y985189I-10J6941D01*
G01X714432D01*
X714566Y985323D01*
X714624Y985335D01*
G03X719980Y990691I-1435J6791D01*
G01X719992Y990749D01*
X720126Y990883D01*
Y991899D01*
G03X720130Y992125I-6937J236D01*
G01Y1015106D01*
X742468D01*
Y994291D01*
G03X742472Y994068I6744J9D01*
G01Y993048D01*
X742610Y992910D01*
X742623Y992852D01*
Y992851D01*
G03X755802I6590J1440D01*
G01Y992852D01*
X755815Y992910D01*
X755953Y993048D01*
Y994068D01*
G03X755957Y994291I-6740J232D01*
G01Y1015106D01*
X794043D01*
Y992125D01*
G03X794047Y991899I6941J10D01*
G01Y990883D01*
X794181Y990749D01*
X794193Y990691D01*
G03X799549Y985335I6791J1435D01*
G01X799607Y985323D01*
X799741Y985189D01*
X800757D01*
G03X800983Y985185I236J6937D01*
G01X902165D01*
G02X918846Y968504I0J-16681D01*
G01Y775590D01*
G03X918850Y775364I6941J10D01*
G01Y774348D01*
X918984Y774215D01*
X918996Y774157D01*
G03X924353Y768800I6791J1434D01*
G01X924411Y768788D01*
X924544Y768654D01*
X925560D01*
G03X925786Y768650I236J6937D01*
G01X984844D01*
G03X985070Y768654I-10J6941D01*
G01X986086D01*
X986220Y768788D01*
X986278Y768800D01*
G03X991634Y774156I-1435J6791D01*
G01X991646Y774214D01*
X991780Y774348D01*
Y775364D01*
G03X991784Y775590I-6937J236D01*
G01Y968504D01*
G02X1008465Y985185I16681J0D01*
G01X1380315D01*
G37*
%LPD*%
G75*
G36*
G01X1346017Y522900D02*
G02X1345206Y523712I1J812D01*
G01Y526312D01*
G02X1346017Y527124I811J1D01*
G01X1348617D01*
G02X1349428Y526312I-1J-812D01*
G01Y523712D01*
G02X1348617Y522900I-811J-1D01*
G01X1346017D01*
G37*
G36*
G01Y530900D02*
G02X1345206Y531712I1J812D01*
G01Y534312D01*
G02X1346017Y535124I811J1D01*
G01X1348617D01*
G02X1349428Y534312I-1J-812D01*
G01Y531712D01*
G02X1348617Y530900I-811J-1D01*
G01X1346017D01*
G37*
G36*
G01X1332017Y527124D02*
G02X1332828Y526312I-1J-812D01*
G01Y523712D01*
G02X1332017Y522900I-811J-1D01*
G01X1329417D01*
G02X1328606Y523712I1J812D01*
G01Y526312D01*
G02X1329417Y527124I811J1D01*
G01X1332017D01*
G37*
G36*
G01Y535124D02*
G02X1332828Y534312I-1J-812D01*
G01Y531712D01*
G02X1332017Y530900I-811J-1D01*
G01X1329417D01*
G02X1328606Y531712I1J812D01*
G01Y534312D01*
G02X1329417Y535124I811J1D01*
G01X1332017D01*
G37*
G36*
G01X465766Y879900D02*
G02X466578Y880712I812J0D01*
G01X467978D01*
G02X468790Y879900I0J-812D01*
G01Y878500D01*
G02X467978Y877688I-812J0D01*
G01X466578D01*
G02X465766Y878500I0J812D01*
G01Y879900D01*
G37*
G36*
G01X461266Y806000D02*
G02X462078Y806812I812J0D01*
G01X463478D01*
G02X464290Y806000I0J-812D01*
G01Y804600D01*
G02X463478Y803788I-812J0D01*
G01X462078D01*
G02X461266Y804600I0J812D01*
G01Y806000D01*
G37*
G36*
G01X459266Y879900D02*
G02X460078Y880712I812J0D01*
G01X461478D01*
G02X462290Y879900I0J-812D01*
G01Y878500D01*
G02X461478Y877688I-812J0D01*
G01X460078D01*
G02X459266Y878500I0J812D01*
G01Y879900D01*
G37*
G36*
G01X454766Y806000D02*
G02X455578Y806812I812J0D01*
G01X456978D01*
G02X457790Y806000I0J-812D01*
G01Y804600D01*
G02X456978Y803788I-812J0D01*
G01X455578D01*
G02X454766Y804600I0J812D01*
G01Y806000D01*
G37*
G36*
G01X429766Y879900D02*
G02X430578Y880712I812J0D01*
G01X431978D01*
G02X432790Y879900I0J-812D01*
G01Y878500D01*
G02X431978Y877688I-812J0D01*
G01X430578D01*
G02X429766Y878500I0J812D01*
G01Y879900D01*
G37*
G36*
G01X439290Y871600D02*
G02X438478Y870788I-812J0D01*
G01X437078D01*
G02X436266Y871600I0J812D01*
G01Y873000D01*
G02X437078Y873812I812J0D01*
G01X438478D01*
G02X439290Y873000I0J-812D01*
G01Y871600D01*
G37*
G36*
G01X430266Y806000D02*
G02X431078Y806812I812J0D01*
G01X432478D01*
G02X433290Y806000I0J-812D01*
G01Y804600D01*
G02X432478Y803788I-812J0D01*
G01X431078D01*
G02X430266Y804600I0J812D01*
G01Y806000D01*
G37*
G36*
G01X423766D02*
G02X424578Y806812I812J0D01*
G01X425978D01*
G02X426790Y806000I0J-812D01*
G01Y804600D01*
G02X425978Y803788I-812J0D01*
G01X424578D01*
G02X423766Y804600I0J812D01*
G01Y806000D01*
G37*
G36*
G01X1123260Y727579D02*
X1120812Y727928D01*
X1120781Y727923D01*
G02X1121211Y730936I-281J1577D01*
G01X1121240Y730921D01*
X1123688Y730572D01*
X1123720Y730577D01*
G02X1123289Y727564I280J-1577D01*
G01X1123260Y727579D01*
G37*
G36*
G01X1180141Y690540D02*
X1180172Y690530D01*
X1182283Y690559D01*
X1182314Y690570D01*
G02X1182354Y687726I503J-1415D01*
G01X1182323Y687736D01*
X1180212Y687707D01*
X1180181Y687696D01*
G02X1180141Y690540I-503J1415D01*
G37*
G36*
G01X1192392Y682405D02*
X1192363Y682415D01*
X1190322Y682510D01*
X1190293Y682502D01*
G02X1190435Y685559I-403J1551D01*
G01X1190464Y685549D01*
X1192505Y685454D01*
X1192534Y685462D01*
G02X1192392Y682405I403J-1551D01*
G37*
G36*
G01X1379639Y609381D02*
G03Y608848I298J-266D01*
G02X1376353I-1643J-1466D01*
G03Y609381I-298J267D01*
G02X1379639I1643J1466D01*
G37*
G36*
G01X1382336Y600343D02*
Y600007D01*
X1382402Y599948D01*
G02X1379448I-1477J-1633D01*
G01X1379514Y600007D01*
Y600343D01*
X1379448Y600402D01*
G02X1382402I1477J1633D01*
G01X1382336Y600343D01*
G37*
G36*
G01X1383443Y579784D02*
X1383107D01*
X1383048Y579718D01*
G02Y582672I-1633J1477D01*
G01X1383107Y582606D01*
X1383443D01*
X1383502Y582672D01*
G02Y579718I1633J-1477D01*
G01X1383443Y579784D01*
G37*
G36*
G01X1343928Y531712D02*
G02X1343117Y530900I-811J-1D01*
G01X1340417D01*
G02X1339606Y531712I1J812D01*
G01Y534312D01*
G02X1340417Y535124I811J1D01*
G01X1343117D01*
G02X1343928Y534312I-1J-812D01*
G01Y531712D01*
G37*
G36*
G01X1338428D02*
G02X1337617Y530900I-811J-1D01*
G01X1334917D01*
G02X1334106Y531712I1J812D01*
G01Y534312D01*
G02X1334917Y535124I811J1D01*
G01X1337617D01*
G02X1338428Y534312I-1J-812D01*
G01Y531712D01*
G37*
G36*
G01X1343928Y523712D02*
G02X1343117Y522900I-811J-1D01*
G01X1340417D01*
G02X1339606Y523712I1J812D01*
G01Y526312D01*
G02X1340417Y527124I811J1D01*
G01X1343117D01*
G02X1343928Y526312I-1J-812D01*
G01Y523712D01*
G37*
G36*
G01X1338428D02*
G02X1337617Y522900I-811J-1D01*
G01X1334917D01*
G02X1334106Y523712I1J812D01*
G01Y526312D01*
G02X1334917Y527124I811J1D01*
G01X1337617D01*
G02X1338428Y526312I-1J-812D01*
G01Y523712D01*
G37*
G36*
G01X469326Y408344D02*
Y405437D01*
X469336Y405405D01*
G02X466492I-1422J-483D01*
G01X466502Y405437D01*
Y408344D01*
X466492Y408376D01*
G02X469336I1422J483D01*
G01X469326Y408344D01*
G37*
G36*
G01X465388D02*
Y405437D01*
X465399Y405405D01*
G02X462555I-1422J-483D01*
G01X462566Y405437D01*
Y408344D01*
X462555Y408376D01*
G02X465399I1422J483D01*
G01X465388Y408344D01*
G37*
G36*
G01X449638D02*
Y405437D01*
X449649Y405405D01*
G02X446805I-1422J-483D01*
G01X446816Y405437D01*
Y408344D01*
X446805Y408376D01*
G02X449649I1422J483D01*
G01X449638Y408344D01*
G37*
G36*
G01X445702D02*
Y405437D01*
X445712Y405405D01*
G02X442868I-1422J-483D01*
G01X442878Y405437D01*
Y408344D01*
X442868Y408376D01*
G02X445712I1422J483D01*
G01X445702Y408344D01*
G37*
G36*
G01X441764D02*
Y405437D01*
X441775Y405405D01*
G02X438931I-1422J-483D01*
G01X438942Y405437D01*
Y408344D01*
X438931Y408376D01*
G02X441775I1422J483D01*
G01X441764Y408344D01*
G37*
G36*
G01X437828D02*
Y405437D01*
X437838Y405405D01*
G02X434994I-1422J-483D01*
G01X435004Y405437D01*
Y408344D01*
X434994Y408376D01*
G02X437838I1422J483D01*
G01X437828Y408344D01*
G37*
G36*
G01X433890D02*
Y405437D01*
X433901Y405405D01*
G02X431057I-1422J-483D01*
G01X431068Y405437D01*
Y408344D01*
X431057Y408376D01*
G02X433901I1422J483D01*
G01X433890Y408344D01*
G37*
G36*
G01X429954D02*
Y405437D01*
X429964Y405405D01*
G02X427120I-1422J-483D01*
G01X427130Y405437D01*
Y408344D01*
X427120Y408376D01*
G02X429964I1422J483D01*
G01X429954Y408344D01*
G37*
G36*
G01X426016D02*
Y405437D01*
X426027Y405405D01*
G02X423183I-1422J-483D01*
G01X423194Y405437D01*
Y408344D01*
X423183Y408376D01*
G02X426027I1422J483D01*
G01X426016Y408344D01*
G37*
G36*
G01X422080D02*
Y405437D01*
X422090Y405405D01*
G02X419246I-1422J-483D01*
G01X419256Y405437D01*
Y408344D01*
X419246Y408376D01*
G02X422090I1422J483D01*
G01X422080Y408344D01*
G37*
G36*
G01X457634Y408268D02*
Y405398D01*
X457645Y405366D01*
G02X454801I-1422J-483D01*
G01X454812Y405398D01*
Y408268D01*
X454801Y408300D01*
G02X457645I1422J483D01*
G01X457634Y408268D01*
G37*
G36*
G01X453634D02*
Y405398D01*
X453645Y405366D01*
G02X450801I-1422J-483D01*
G01X450812Y405398D01*
Y408268D01*
X450801Y408300D01*
G02X453645I1422J483D01*
G01X453634Y408268D01*
G37*
G36*
G01X74347Y386464D02*
X73619D01*
G02Y389488I-1736J1512D01*
G01X74347D01*
G02Y386464I1736J-1512D01*
G37*
G36*
G01X64795Y386309D02*
X64553Y386302D01*
X64496Y386238D01*
G02X64410Y389404I-1713J1538D01*
G01X64471Y389343D01*
X64713Y389350D01*
X64770Y389414D01*
G02X64856Y386248I1713J-1538D01*
G01X64795Y386309D01*
G37*
G36*
G01X45413Y389489D02*
G03X45946Y389490I266J299D01*
G02X45953Y386056I1537J-1714D01*
G03X45420Y386055I-266J-299D01*
G02X45413Y389489I-1537J1714D01*
G37*
G36*
G01X55229Y386273D02*
X55000Y386260D01*
X54945Y386194D01*
G02X54774Y389339I-1762J1481D01*
G01X54837Y389279D01*
X55066Y389292D01*
X55122Y389358D01*
G02X55291Y386213I1761J-1482D01*
G01X55229Y386273D01*
G37*
G36*
G01X484136Y370835D02*
X484168Y370825D01*
X487061Y370884D01*
X487092Y370895D01*
G02X487150Y368051I511J-1412D01*
G01X487118Y368061D01*
X484225Y368002D01*
X484194Y367991D01*
G02X484136Y370835I-511J1412D01*
G37*
G36*
G01X485085Y364979D02*
X485074Y364948D01*
Y362127D01*
X485084Y362096D01*
G02X482240Y362097I-1422J-483D01*
G01X482251Y362128D01*
Y364949D01*
X482241Y364980D01*
G02X485085Y364979I1422J483D01*
G37*
G36*
G01X522012Y361968D02*
Y359469D01*
X522022Y359438D01*
G02X518978I-1522J-501D01*
G01X518988Y359469D01*
Y361968D01*
X518978Y361999D01*
G02X522022I1522J501D01*
G01X522012Y361968D01*
G37*
G36*
G01X487084Y356264D02*
X484177D01*
X484145Y356254D01*
G02Y359098I-483J1422D01*
G01X484177Y359088D01*
X487084D01*
X487116Y359098D01*
G02Y356254I483J-1422D01*
G01X487084Y356264D01*
G37*
G36*
G01X164909Y353198D02*
X164539D01*
X164480Y353134D01*
G02Y356284I-1679J1575D01*
G01X164539Y356220D01*
X164909D01*
X164968Y356284D01*
G02Y353134I1679J-1575D01*
G01X164909Y353198D01*
G37*
G36*
G01X153409D02*
X153039D01*
X152980Y353134D01*
G02Y356284I-1679J1575D01*
G01X153039Y356220D01*
X153409D01*
X153468Y356284D01*
G02Y353134I1679J-1575D01*
G01X153409Y353198D01*
G37*
G36*
G01X141409D02*
X141039D01*
X140980Y353134D01*
G02Y356284I-1679J1575D01*
G01X141039Y356220D01*
X141409D01*
X141468Y356284D01*
G02Y353134I1679J-1575D01*
G01X141409Y353198D01*
G37*
G36*
G01X129409D02*
X129039D01*
X128980Y353134D01*
G02Y356284I-1679J1575D01*
G01X129039Y356220D01*
X129409D01*
X129468Y356284D01*
G02Y353134I1679J-1575D01*
G01X129409Y353198D01*
G37*
G36*
G01X487084Y352328D02*
X484177D01*
X484145Y352317D01*
G02Y355161I-483J1422D01*
G01X484177Y355150D01*
X487084D01*
X487116Y355161D01*
G02Y352317I483J-1422D01*
G01X487084Y352328D01*
G37*
G36*
G01X528012Y356000D02*
Y353501D01*
X528022Y353470D01*
G02X524978I-1522J-501D01*
G01X524988Y353501D01*
Y356000D01*
X524978Y356031D01*
G02X528022I1522J501D01*
G01X528012Y356000D01*
G37*
G36*
G01X522012Y350968D02*
Y348469D01*
X522022Y348438D01*
G02X518978I-1522J-501D01*
G01X518988Y348469D01*
Y350968D01*
X518978Y350999D01*
G02X522022I1522J501D01*
G01X522012Y350968D01*
G37*
G36*
G01X1198147Y342875D02*
G03X1197613I-267J-298D01*
G02Y346301I-1538J1713D01*
G03X1198147I267J298D01*
G02Y342875I1538J-1713D01*
G37*
G36*
G01X528012Y346000D02*
Y343501D01*
X528022Y343470D01*
G02X524978I-1522J-501D01*
G01X524988Y343501D01*
Y346000D01*
X524978Y346031D01*
G02X528022I1522J501D01*
G01X528012Y346000D01*
G37*
G36*
G01X194386Y343719D02*
Y343349D01*
X194449Y343290D01*
G02X191299I-1575J-1679D01*
G01X191362Y343349D01*
Y343719D01*
X191299Y343778D01*
G02X194449I1575J1679D01*
G01X194386Y343719D01*
G37*
G36*
G01X486937Y332441D02*
X486906Y332453D01*
X484094Y332615D01*
X484062Y332606D01*
G02X484225Y335446I-400J1448D01*
G01X484256Y335434D01*
X487068Y335272D01*
X487100Y335281D01*
G02X486937Y332441I400J-1448D01*
G37*
G36*
G01X487084Y328706D02*
X484177D01*
X484145Y328695D01*
G02Y331539I-483J1422D01*
G01X484177Y331528D01*
X487084D01*
X487116Y331539D01*
G02Y328695I483J-1422D01*
G01X487084Y328706D01*
G37*
G36*
G01X194386Y332569D02*
Y332199D01*
X194449Y332140D01*
G02X191299I-1575J-1679D01*
G01X191362Y332199D01*
Y332569D01*
X191299Y332628D01*
G02X194449I1575J1679D01*
G01X194386Y332569D01*
G37*
G36*
G01X177884Y327238D02*
X177514D01*
X177455Y327174D01*
G02Y330324I-1679J1575D01*
G01X177514Y330260D01*
X177884D01*
X177943Y330324D01*
G02Y327174I1679J-1575D01*
G01X177884Y327238D01*
G37*
G36*
G01X166255Y327188D02*
X165885D01*
X165826Y327124D01*
G02Y330274I-1679J1575D01*
G01X165885Y330210D01*
X166255D01*
X166314Y330274D01*
G02Y327124I1679J-1575D01*
G01X166255Y327188D01*
G37*
G36*
G01X487084Y324768D02*
X484177D01*
X484145Y324758D01*
G02Y327602I-483J1422D01*
G01X484177Y327592D01*
X487084D01*
X487116Y327602D01*
G02Y324758I483J-1422D01*
G01X487084Y324768D01*
G37*
G36*
G01X532970Y323988D02*
X530380D01*
X530349Y323978D01*
G02Y327022I-501J1522D01*
G01X530380Y327012D01*
X532970D01*
X533001Y327022D01*
G02Y323978I501J-1522D01*
G01X532970Y323988D01*
G37*
G36*
G01X1171587Y322003D02*
G03X1171053I-267J-298D01*
G02Y325429I-1538J1713D01*
G03X1171587I267J298D01*
G02Y322003I1538J-1713D01*
G37*
G36*
G01X157386Y325219D02*
Y324849D01*
X157449Y324790D01*
G02X154299I-1575J-1679D01*
G01X154362Y324849D01*
Y325219D01*
X154299Y325278D01*
G02X157449I1575J1679D01*
G01X157386Y325219D01*
G37*
G36*
G01X538082Y319488D02*
X535492D01*
X535461Y319478D01*
G02Y322522I-501J1522D01*
G01X535492Y322512D01*
X538082D01*
X538113Y322522D01*
G02Y319478I501J-1522D01*
G01X538082Y319488D01*
G37*
G36*
G01X511468Y318488D02*
X509032D01*
X509001Y318478D01*
G02Y321522I-501J1522D01*
G01X509032Y321512D01*
X511468D01*
X511499Y321522D01*
G02Y318478I501J-1522D01*
G01X511468Y318488D01*
G37*
G36*
G01X1254788Y322854D02*
Y322146D01*
X1254844Y322088D01*
G02X1251510I-1667J-1588D01*
G01X1251566Y322146D01*
Y322854D01*
X1251510Y322912D01*
G02X1254844I1667J1588D01*
G01X1254788Y322854D01*
G37*
G36*
G01X526470Y317848D02*
X523880D01*
X523849Y317837D01*
G02Y320881I-501J1522D01*
G01X523880Y320870D01*
X526470D01*
X526501Y320881D01*
G02Y317837I501J-1522D01*
G01X526470Y317848D01*
G37*
G36*
G01X494571Y314440D02*
X491789D01*
X491758Y314430D01*
G02Y317474I-501J1522D01*
G01X491789Y317464D01*
X494571D01*
X494602Y317474D01*
G02Y314430I501J-1522D01*
G01X494571Y314440D01*
G37*
G36*
G01X502715Y312688D02*
X502345D01*
X502286Y312625D01*
G02Y315775I-1679J1575D01*
G01X502345Y315712D01*
X502715D01*
X502774Y315775D01*
G02Y312625I1679J-1575D01*
G01X502715Y312688D01*
G37*
G36*
G01X517968Y312488D02*
X517598D01*
X517539Y312425D01*
G02Y315575I-1679J1575D01*
G01X517598Y315512D01*
X517968D01*
X518027Y315575D01*
G02Y312425I1679J-1575D01*
G01X517968Y312488D01*
G37*
G36*
G01X157386Y316069D02*
Y315699D01*
X157449Y315640D01*
G02X154299I-1575J-1679D01*
G01X154362Y315699D01*
Y316069D01*
X154299Y316128D01*
G02X157449I1575J1679D01*
G01X157386Y316069D01*
G37*
G36*
G01X1157813Y314867D02*
G03Y314333I298J-267D01*
G02X1154387I-1713J-1538D01*
G03Y314867I-298J267D01*
G02X1157813I1713J1538D01*
G37*
G36*
G01X1251863Y310336D02*
X1251916Y310395D01*
X1251897Y311124D01*
X1251842Y311180D01*
G02X1255191Y311264I1635J1620D01*
G01X1255138Y311205D01*
X1255157Y310476D01*
X1255212Y310420D01*
G02X1251863Y310336I-1635J-1620D01*
G37*
G36*
G01X837077Y308776D02*
X837092Y308845D01*
X835080Y312871D01*
X835016Y312901D01*
G02X839696Y315239I1403J3044D01*
G01X839681Y315170D01*
X841693Y311144D01*
X841757Y311114D01*
G02X837077Y308776I-1403J-3044D01*
G37*
G36*
G01X1166713Y306637D02*
G03Y306103I298J-267D01*
G02X1163287I-1713J-1538D01*
G03Y306637I-298J267D01*
G02X1166713I1713J1538D01*
G37*
G36*
G01X616607Y308775D02*
X616622Y308844D01*
X614607Y312870D01*
X614543Y312900D01*
G02X619221Y315240I1401J3045D01*
G01X619206Y315171D01*
X621221Y311145D01*
X621285Y311115D01*
G02X620256Y304739I-1401J-3045D01*
G03X619934Y304180I44J-398D01*
G02X616149Y301675I-2106J-930D01*
G01X616090Y301738D01*
X615700D01*
X615641Y301675D01*
G02Y304825I-1679J1575D01*
G01X615700Y304762D01*
X616090D01*
X616149Y304825D01*
G02X617041Y305413I1678J-1575D01*
G03X617222Y306032I-136J376D01*
G02X616607Y308775I2662J2037D01*
G37*
G36*
G01X1262188Y298322D02*
Y297748D01*
X1262244Y297690D01*
G02X1258910I-1667J-1588D01*
G01X1258966Y297748D01*
Y298322D01*
X1258910Y298380D01*
G02X1262244I1667J1588D01*
G01X1262188Y298322D01*
G37*
G36*
G01X211995Y293398D02*
X211625D01*
X211566Y293334D01*
G02Y296484I-1679J1575D01*
G01X211625Y296420D01*
X211995D01*
X212054Y296484D01*
G02Y293334I1679J-1575D01*
G01X211995Y293398D01*
G37*
G36*
G01X202547D02*
X202177D01*
X202118Y293334D01*
G02Y296484I-1679J1575D01*
G01X202177Y296420D01*
X202547D01*
X202606Y296484D01*
G02Y293334I1679J-1575D01*
G01X202547Y293398D01*
G37*
G36*
G01X177350D02*
X176980D01*
X176921Y293334D01*
G02Y296484I-1679J1575D01*
G01X176980Y296420D01*
X177350D01*
X177409Y296484D01*
G02Y293334I1679J-1575D01*
G01X177350Y293398D01*
G37*
G36*
G01X167901Y292798D02*
X167531D01*
X167472Y292734D01*
G02Y295884I-1679J1575D01*
G01X167531Y295820D01*
X167901D01*
X167960Y295884D01*
G02Y292734I1679J-1575D01*
G01X167901Y292798D01*
G37*
G36*
G01X1172039Y288614D02*
X1171515D01*
X1171456Y288550D01*
G02Y291700I-1679J1575D01*
G01X1171515Y291636D01*
X1172039D01*
X1172098Y291700D01*
G02Y288550I1679J-1575D01*
G01X1172039Y288614D01*
G37*
G36*
G01X1191005Y288288D02*
X1190615D01*
X1190556Y288225D01*
G02Y291375I-1679J1575D01*
G01X1190615Y291312D01*
X1191005D01*
X1191064Y291375D01*
G02Y288225I1679J-1575D01*
G01X1191005Y288288D01*
G37*
G36*
G01X811393Y293400D02*
X811457Y293430D01*
X813472Y297456D01*
X813457Y297525D01*
G02X818135Y295185I3277J705D01*
G01X818071Y295155D01*
X816056Y291128D01*
X816071Y291060D01*
G02X811393Y293400I-3277J-705D01*
G37*
G36*
G01X805582Y308775D02*
X805597Y308844D01*
X803582Y312870D01*
X803518Y312900D01*
G02X808196Y315240I1401J3045D01*
G01X808181Y315171D01*
X810196Y311145D01*
X810260Y311115D01*
G02X809235Y304739I-1401J-3045D01*
G03X808914Y304180I45J-397D01*
G02X805129Y301675I-2106J-930D01*
G01X805070Y301738D01*
X804680D01*
X804621Y301675D01*
G02X803685Y301071I-1679J1575D01*
G03X803513Y300430I130J-378D01*
G02X802387Y295186I-2529J-2200D01*
G01X802323Y295156D01*
X800311Y291130D01*
X800326Y291062D01*
G02X795646Y293399I-3277J-707D01*
G01X795710Y293429D01*
X797722Y297455D01*
X797707Y297524D01*
G02X800613Y301561I3277J706D01*
G03X800920Y302150I-44J398D01*
G02X804621Y304825I2022J1100D01*
G01X804680Y304762D01*
X805070D01*
X805129Y304825D01*
G02X806018Y305412I1678J-1575D01*
G03X806198Y306031I-137J376D01*
G02X805582Y308775I2661J2039D01*
G37*
G36*
G01X789832Y308776D02*
X789847Y308845D01*
X787835Y312871D01*
X787771Y312901D01*
G02X792451Y315239I1403J3044D01*
G01X792436Y315170D01*
X794448Y311144D01*
X794512Y311114D01*
G02X793485Y304739I-1403J-3044D01*
G03X793164Y304180I45J-397D01*
G02X789379Y301675I-2106J-930D01*
G01X789320Y301738D01*
X788930D01*
X788871Y301675D01*
G02X787935Y301071I-1679J1575D01*
G03X787763Y300430I130J-378D01*
G02X786637Y295186I-2529J-2200D01*
G01X786573Y295156D01*
X784561Y291130D01*
X784576Y291062D01*
G02X779896Y293399I-3277J-707D01*
G01X779960Y293429D01*
X781972Y297455D01*
X781957Y297524D01*
G02X784863Y301561I3277J706D01*
G03X785170Y302150I-44J398D01*
G02X788871Y304825I2022J1100D01*
G01X788930Y304762D01*
X789320D01*
X789379Y304825D01*
G02X790268Y305412I1678J-1575D01*
G03X790448Y306031I-137J376D01*
G02X789832Y308776I2661J2039D01*
G37*
G36*
G01X774087Y308775D02*
X774102Y308844D01*
X772087Y312870D01*
X772023Y312900D01*
G02X776701Y315240I1401J3045D01*
G01X776686Y315171D01*
X778701Y311145D01*
X778765Y311115D01*
G02X777740Y304739I-1401J-3045D01*
G03X777419Y304180I45J-397D01*
G02X773634Y301675I-2106J-930D01*
G01X773575Y301738D01*
X773185D01*
X773126Y301675D01*
G02X772190Y301071I-1679J1575D01*
G03X772018Y300430I130J-378D01*
G02X770890Y295185I-2529J-2200D01*
G01X770826Y295155D01*
X768811Y291128D01*
X768826Y291060D01*
G02X764148Y293400I-3277J-705D01*
G01X764212Y293430D01*
X766227Y297456D01*
X766212Y297525D01*
G02X769118Y301561I3277J705D01*
G03X769425Y302150I-44J398D01*
G02X773126Y304825I2022J1100D01*
G01X773185Y304762D01*
X773575D01*
X773634Y304825D01*
G02X774523Y305412I1678J-1575D01*
G03X774703Y306031I-137J376D01*
G02X774087Y308775I2661J2039D01*
G37*
G36*
G01X758337Y308776D02*
X758352Y308845D01*
X756340Y312871D01*
X756276Y312901D01*
G02X760956Y315239I1403J3044D01*
G01X760941Y315170D01*
X762953Y311144D01*
X763017Y311114D01*
G02X761990Y304739I-1403J-3044D01*
G03X761669Y304180I45J-397D01*
G02X757884Y301675I-2106J-930D01*
G01X757825Y301738D01*
X757435D01*
X757376Y301675D01*
G02X756440Y301071I-1679J1575D01*
G03X756268Y300430I130J-378D01*
G02X755142Y295186I-2529J-2200D01*
G01X755078Y295156D01*
X753066Y291130D01*
X753081Y291062D01*
G02X748401Y293399I-3277J-707D01*
G01X748465Y293429D01*
X750477Y297455D01*
X750462Y297524D01*
G02X753368Y301561I3277J706D01*
G03X753675Y302150I-44J398D01*
G02X757376Y304825I2022J1100D01*
G01X757435Y304762D01*
X757825D01*
X757884Y304825D01*
G02X758773Y305412I1678J-1575D01*
G03X758953Y306031I-137J376D01*
G02X758337Y308776I2661J2039D01*
G37*
G36*
G01X669661Y293399D02*
X669725Y293429D01*
X671737Y297455D01*
X671722Y297524D01*
G02X676402Y295186I3277J706D01*
G01X676338Y295156D01*
X674326Y291130D01*
X674341Y291062D01*
G02X669661Y293399I-3277J-707D01*
G37*
G36*
G01X663847Y308776D02*
X663862Y308845D01*
X661850Y312871D01*
X661786Y312901D01*
G02X666466Y315239I1403J3044D01*
G01X666451Y315170D01*
X668463Y311144D01*
X668527Y311114D01*
G02X667500Y304739I-1403J-3044D01*
G03X667179Y304180I45J-397D01*
G02X663394Y301675I-2106J-930D01*
G01X663335Y301738D01*
X662945D01*
X662886Y301675D01*
G02X661954Y301072I-1680J1574D01*
G03X661782Y300431I129J-378D01*
G02X660655Y295185I-2528J-2201D01*
G01X660591Y295155D01*
X658576Y291128D01*
X658591Y291060D01*
G02X653913Y293400I-3277J-705D01*
G01X653977Y293430D01*
X655992Y297456D01*
X655977Y297525D01*
G02X658879Y301561I3277J705D01*
G03X659185Y302150I-45J397D01*
G02X662886Y304825I2022J1100D01*
G01X662945Y304762D01*
X663335D01*
X663394Y304825D01*
G02X664283Y305412I1678J-1575D01*
G03X664463Y306031I-137J376D01*
G02X663847Y308776I2661J2039D01*
G37*
G36*
G01X648102Y308775D02*
X648117Y308844D01*
X646102Y312870D01*
X646038Y312900D01*
G02X650716Y315240I1401J3045D01*
G01X650701Y315171D01*
X652716Y311145D01*
X652780Y311115D01*
G02X651751Y304739I-1401J-3045D01*
G03X651429Y304180I44J-398D01*
G02X647644Y301675I-2106J-930D01*
G01X647585Y301738D01*
X647195D01*
X647136Y301675D01*
G02X646204Y301072I-1680J1574D01*
G03X646032Y300431I129J-378D01*
G02X644907Y295186I-2528J-2201D01*
G01X644843Y295156D01*
X642831Y291130D01*
X642846Y291062D01*
G02X638166Y293399I-3277J-707D01*
G01X638230Y293429D01*
X640242Y297455D01*
X640227Y297524D01*
G02X643129Y301561I3277J706D01*
G03X643435Y302150I-45J397D01*
G02X647136Y304825I2022J1100D01*
G01X647195Y304762D01*
X647585D01*
X647644Y304825D01*
G02X648536Y305413I1678J-1575D01*
G03X648717Y306032I-136J376D01*
G02X648102Y308775I2662J2037D01*
G37*
G36*
G01X622416Y293399D02*
X622480Y293429D01*
X624492Y297455D01*
X624477Y297524D01*
G02X627383Y301561I3277J706D01*
G03X627690Y302150I-44J398D01*
G02X631391Y304825I2022J1100D01*
G01X631450Y304762D01*
X631840D01*
X631899Y304825D01*
G02X632788Y305412I1678J-1575D01*
G03X632968Y306031I-137J376D01*
G02X632352Y308776I2661J2039D01*
G01X632367Y308845D01*
X630355Y312871D01*
X630291Y312901D01*
G02X634971Y315239I1403J3044D01*
G01X634956Y315170D01*
X636968Y311144D01*
X637032Y311114D01*
G02X636005Y304739I-1403J-3044D01*
G03X635684Y304180I45J-397D01*
G02X631899Y301675I-2106J-930D01*
G01X631840Y301738D01*
X631450D01*
X631391Y301675D01*
G02X630455Y301071I-1679J1575D01*
G03X630283Y300430I130J-378D01*
G02X629157Y295186I-2529J-2200D01*
G01X629093Y295156D01*
X627081Y291130D01*
X627096Y291062D01*
G02X622416Y293399I-3277J-707D01*
G37*
G36*
G01X1252288Y285854D02*
Y285146D01*
X1252344Y285088D01*
G02X1249010I-1667J-1588D01*
G01X1249066Y285146D01*
Y285854D01*
X1249010Y285912D01*
G02X1252344I1667J1588D01*
G01X1252288Y285854D01*
G37*
G36*
G01X1256456Y270695D02*
Y270305D01*
X1256519Y270246D01*
G02X1253369I-1575J-1679D01*
G01X1253432Y270305D01*
Y270695D01*
X1253369Y270754D01*
G02X1256519I1575J1679D01*
G01X1256456Y270695D01*
G37*
G36*
G01X309166Y162288D02*
X306384D01*
X306353Y162278D01*
G02Y165322I-501J1522D01*
G01X306384Y165312D01*
X309166D01*
X309197Y165322D01*
G02Y162278I501J-1522D01*
G01X309166Y162288D01*
G37*
G36*
G01X316716Y154488D02*
X313934D01*
X313903Y154478D01*
G02Y157522I-501J1522D01*
G01X313934Y157512D01*
X316716D01*
X316747Y157522D01*
G02Y154478I501J-1522D01*
G01X316716Y154488D01*
G37*
G36*
G01X327934Y151975D02*
Y149476D01*
X327944Y149445D01*
G02X324900I-1522J-501D01*
G01X324910Y149476D01*
Y151975D01*
X324900Y152006D01*
G02X327944I1522J501D01*
G01X327934Y151975D01*
G37*
G36*
G01X329512Y149097D02*
X329522Y149127D01*
X329606Y152153D01*
X329597Y152183D01*
G02X332457Y152104I1443J418D01*
G01X332447Y152074D01*
X332363Y149048D01*
X332372Y149018D01*
G02X329512Y149097I-1443J-418D01*
G37*
G36*
G01X303145Y142816D02*
X301567D01*
G02Y145840I-1736J1512D01*
G01X303145D01*
X303176Y145850D01*
G02Y142806I501J-1522D01*
G01X303145Y142816D01*
G37*
G36*
G01X321312Y146366D02*
Y143584D01*
X321322Y143553D01*
G02X318278I-1522J-501D01*
G01X318288Y143584D01*
Y146366D01*
X318278Y146397D01*
G02X321322I1522J501D01*
G01X321312Y146366D01*
G37*
G36*
G01X328612Y139325D02*
Y136826D01*
X328622Y136795D01*
G02X325578I-1522J-501D01*
G01X325588Y136826D01*
Y139325D01*
X325578Y139356D01*
G02X328622I1522J501D01*
G01X328612Y139325D01*
G37*
G36*
G01X336112Y132499D02*
Y130000D01*
X336122Y129969D01*
G02X333078I-1522J-501D01*
G01X333088Y130000D01*
Y132499D01*
X333078Y132530D01*
G02X336122I1522J501D01*
G01X336112Y132499D01*
G37*
G36*
G01X1092156Y124988D02*
X1091766D01*
X1091707Y124925D01*
G02Y128075I-1679J1575D01*
G01X1091766Y128012D01*
X1092156D01*
X1092215Y128075D01*
G02Y124925I1679J-1575D01*
G01X1092156Y124988D01*
G37*
G36*
G01X401052Y122967D02*
G02X400440Y122356I-612J1D01*
G01X399640D01*
G02X399028Y122967I-1J611D01*
G01Y123967D01*
G02X399148Y124330I612J-1D01*
G03Y124804I-322J237D01*
G02X399028Y125167I492J364D01*
G01Y126167D01*
G02X399640Y126778I612J-1D01*
G01X400440D01*
G02X401052Y126167I1J-611D01*
G01Y125167D01*
G02X400932Y124804I-612J1D01*
G03Y124330I322J-237D01*
G02X401052Y123967I-492J-364D01*
G01Y122967D01*
G37*
G36*
G01X398552D02*
G02X397940Y122356I-612J1D01*
G01X397140D01*
G02X396528Y122967I-1J611D01*
G01Y123967D01*
G02X396648Y124330I612J-1D01*
G03Y124804I-322J237D01*
G02X396528Y125167I492J364D01*
G01Y126167D01*
G02X397140Y126778I612J-1D01*
G01X397940D01*
G02X398552Y126167I1J-611D01*
G01Y125167D01*
G02X398432Y124804I-612J1D01*
G03Y124330I322J-237D01*
G02X398552Y123967I-492J-364D01*
G01Y122967D01*
G37*
G36*
G01X413052Y122900D02*
G02X412440Y122288I-612J0D01*
G01X411640D01*
G02X411028Y122900I0J612D01*
G01Y123900D01*
G02X411148Y124263I612J-1D01*
G03Y124737I-322J237D01*
G02X411028Y125100I492J364D01*
G01Y126100D01*
G02X411640Y126712I612J0D01*
G01X412440D01*
G02X413052Y126100I0J-612D01*
G01Y125100D01*
G02X412932Y124737I-612J1D01*
G03Y124263I322J-237D01*
G02X413052Y123900I-492J-364D01*
G01Y122900D01*
G37*
G36*
G01X410552D02*
G02X409940Y122288I-612J0D01*
G01X409140D01*
G02X408528Y122900I0J612D01*
G01Y123900D01*
G02X408648Y124263I612J-1D01*
G03Y124737I-322J237D01*
G02X408528Y125100I492J364D01*
G01Y126100D01*
G02X409140Y126712I612J0D01*
G01X409940D01*
G02X410552Y126100I0J-612D01*
G01Y125100D01*
G02X410432Y124737I-612J1D01*
G03Y124263I322J-237D01*
G02X410552Y123900I-492J-364D01*
G01Y122900D01*
G37*
G36*
G01X407052D02*
G02X406440Y122288I-612J0D01*
G01X405640D01*
G02X405028Y122900I0J612D01*
G01Y123900D01*
G02X405148Y124263I612J-1D01*
G03Y124737I-322J237D01*
G02X405028Y125100I492J364D01*
G01Y126100D01*
G02X405640Y126712I612J0D01*
G01X406440D01*
G02X407052Y126100I0J-612D01*
G01Y125100D01*
G02X406932Y124737I-612J1D01*
G03Y124263I322J-237D01*
G02X407052Y123900I-492J-364D01*
G01Y122900D01*
G37*
G36*
G01X404552D02*
G02X403940Y122288I-612J0D01*
G01X403140D01*
G02X402528Y122900I0J612D01*
G01Y123900D01*
G02X402648Y124263I612J-1D01*
G03Y124737I-322J237D01*
G02X402528Y125100I492J364D01*
G01Y126100D01*
G02X403140Y126712I612J0D01*
G01X403940D01*
G02X404552Y126100I0J-612D01*
G01Y125100D01*
G02X404432Y124737I-612J1D01*
G03Y124263I322J-237D01*
G02X404552Y123900I-492J-364D01*
G01Y122900D01*
G37*
G36*
G01X395052D02*
G02X394440Y122288I-612J0D01*
G01X393640D01*
G02X393028Y122900I0J612D01*
G01Y123900D01*
G02X393148Y124263I612J-1D01*
G03Y124737I-322J237D01*
G02X393028Y125100I492J364D01*
G01Y126100D01*
G02X393640Y126712I612J0D01*
G01X394440D01*
G02X395052Y126100I0J-612D01*
G01Y125100D01*
G02X394932Y124737I-612J1D01*
G03Y124263I322J-237D01*
G02X395052Y123900I-492J-364D01*
G01Y122900D01*
G37*
G36*
G01X392552D02*
G02X391940Y122288I-612J0D01*
G01X391140D01*
G02X390528Y122900I0J612D01*
G01Y123900D01*
G02X390648Y124263I612J-1D01*
G03Y124737I-322J237D01*
G02X390528Y125100I492J364D01*
G01Y126100D01*
G02X391140Y126712I612J0D01*
G01X391940D01*
G02X392552Y126100I0J-612D01*
G01Y125100D01*
G02X392432Y124737I-612J1D01*
G03Y124263I322J-237D01*
G02X392552Y123900I-492J-364D01*
G01Y122900D01*
G37*
G36*
G01X389052D02*
G02X388440Y122288I-612J0D01*
G01X387640D01*
G02X387028Y122900I0J612D01*
G01Y123900D01*
G02X387148Y124263I612J-1D01*
G03Y124737I-322J237D01*
G02X387028Y125100I492J364D01*
G01Y126100D01*
G02X387640Y126712I612J0D01*
G01X388440D01*
G02X389052Y126100I0J-612D01*
G01Y125100D01*
G02X388932Y124737I-612J1D01*
G03Y124263I322J-237D01*
G02X389052Y123900I-492J-364D01*
G01Y122900D01*
G37*
G36*
G01X386552D02*
G02X385940Y122288I-612J0D01*
G01X385140D01*
G02X384528Y122900I0J612D01*
G01Y123900D01*
G02X384648Y124263I612J-1D01*
G03Y124737I-322J237D01*
G02X384528Y125100I492J364D01*
G01Y126100D01*
G02X385140Y126712I612J0D01*
G01X385940D01*
G02X386552Y126100I0J-612D01*
G01Y125100D01*
G02X386432Y124737I-612J1D01*
G03Y124263I322J-237D01*
G02X386552Y123900I-492J-364D01*
G01Y122900D01*
G37*
G36*
G01X383052D02*
G02X382440Y122288I-612J0D01*
G01X381640D01*
G02X381028Y122900I0J612D01*
G01Y123900D01*
G02X381148Y124263I612J-1D01*
G03Y124737I-322J237D01*
G02X381028Y125100I492J364D01*
G01Y126100D01*
G02X381640Y126712I612J0D01*
G01X382440D01*
G02X383052Y126100I0J-612D01*
G01Y125100D01*
G02X382932Y124737I-612J1D01*
G03Y124263I322J-237D01*
G02X383052Y123900I-492J-364D01*
G01Y122900D01*
G37*
G36*
G01X380552D02*
G02X379940Y122288I-612J0D01*
G01X379140D01*
G02X378528Y122900I0J612D01*
G01Y123900D01*
G02X378648Y124263I612J-1D01*
G03Y124737I-322J237D01*
G02X378528Y125100I492J364D01*
G01Y126100D01*
G02X379140Y126712I612J0D01*
G01X379940D01*
G02X380552Y126100I0J-612D01*
G01Y125100D01*
G02X380432Y124737I-612J1D01*
G03Y124263I322J-237D01*
G02X380552Y123900I-492J-364D01*
G01Y122900D01*
G37*
G36*
G01X377052D02*
G02X376440Y122288I-612J0D01*
G01X375640D01*
G02X375028Y122900I0J612D01*
G01Y123900D01*
G02X375148Y124263I612J-1D01*
G03Y124737I-322J237D01*
G02X375028Y125100I492J364D01*
G01Y126100D01*
G02X375640Y126712I612J0D01*
G01X376440D01*
G02X377052Y126100I0J-612D01*
G01Y125100D01*
G02X376932Y124737I-612J1D01*
G03Y124263I322J-237D01*
G02X377052Y123900I-492J-364D01*
G01Y122900D01*
G37*
G36*
G01X374552D02*
G02X373940Y122288I-612J0D01*
G01X373140D01*
G02X372528Y122900I0J612D01*
G01Y123900D01*
G02X372648Y124263I612J-1D01*
G03Y124737I-322J237D01*
G02X372528Y125100I492J364D01*
G01Y126100D01*
G02X373140Y126712I612J0D01*
G01X373940D01*
G02X374552Y126100I0J-612D01*
G01Y125100D01*
G02X374432Y124737I-612J1D01*
G03Y124263I322J-237D01*
G02X374552Y123900I-492J-364D01*
G01Y122900D01*
G37*
G36*
G01X371052D02*
G02X370440Y122288I-612J0D01*
G01X369640D01*
G02X369028Y122900I0J612D01*
G01Y123900D01*
G02X369148Y124263I612J-1D01*
G03Y124737I-322J237D01*
G02X369028Y125100I492J364D01*
G01Y126100D01*
G02X369640Y126712I612J0D01*
G01X370440D01*
G02X371052Y126100I0J-612D01*
G01Y125100D01*
G02X370932Y124737I-612J1D01*
G03Y124263I322J-237D01*
G02X371052Y123900I-492J-364D01*
G01Y122900D01*
G37*
G36*
G01X368552D02*
G02X367940Y122288I-612J0D01*
G01X367140D01*
G02X366528Y122900I0J612D01*
G01Y123900D01*
G02X366648Y124263I612J-1D01*
G03Y124737I-322J237D01*
G02X366528Y125100I492J364D01*
G01Y126100D01*
G02X367140Y126712I612J0D01*
G01X367940D01*
G02X368552Y126100I0J-612D01*
G01Y125100D01*
G02X368432Y124737I-612J1D01*
G03Y124263I322J-237D01*
G02X368552Y123900I-492J-364D01*
G01Y122900D01*
G37*
G36*
G01X1072448Y40156D02*
X1069284D01*
G02Y46378I-2355J3111D01*
G01X1072448D01*
G02Y40156I2355J-3111D01*
G37*
G36*
G01X438478Y874288D02*
X437078D01*
G02X436266Y875100I0J812D01*
G01Y876500D01*
G02X436620Y877170I811J0D01*
G03Y877830I-226J330D01*
G02X436266Y878500I457J670D01*
G01Y879900D01*
G02X437078Y880712I812J0D01*
G01X438478D01*
G02X439290Y879900I0J-812D01*
G01Y878500D01*
G02X438936Y877830I-811J0D01*
G03Y877170I226J-330D01*
G02X439290Y876500I-457J-670D01*
G01Y875100D01*
G02X438478Y874288I-812J0D01*
G37*
G36*
G01X467978Y870788D02*
X466578D01*
G02X465766Y871600I0J812D01*
G01Y873000D01*
G02X466120Y873670I811J0D01*
G03Y874330I-226J330D01*
G02X465766Y875000I457J670D01*
G01Y876400D01*
G02X466578Y877212I812J0D01*
G01X467978D01*
G02X468790Y876400I0J-812D01*
G01Y875000D01*
G02X468436Y874330I-811J0D01*
G03Y873670I226J-330D01*
G02X468790Y873000I-457J-670D01*
G01Y871600D01*
G02X467978Y870788I-812J0D01*
G37*
G36*
G01X461478D02*
X460078D01*
G02X459266Y871600I0J812D01*
G01Y873000D01*
G02X459620Y873670I811J0D01*
G03Y874330I-226J330D01*
G02X459266Y875000I457J670D01*
G01Y876400D01*
G02X460078Y877212I812J0D01*
G01X461478D01*
G02X462290Y876400I0J-812D01*
G01Y875000D01*
G02X461936Y874330I-811J0D01*
G03Y873670I226J-330D01*
G02X462290Y873000I-457J-670D01*
G01Y871600D01*
G02X461478Y870788I-812J0D01*
G37*
G36*
G01X431978D02*
X430578D01*
G02X429766Y871600I0J812D01*
G01Y873000D01*
G02X430120Y873670I811J0D01*
G03Y874330I-226J330D01*
G02X429766Y875000I457J670D01*
G01Y876400D01*
G02X430578Y877212I812J0D01*
G01X431978D01*
G02X432790Y876400I0J-812D01*
G01Y875000D01*
G02X432436Y874330I-811J0D01*
G03Y873670I226J-330D01*
G02X432790Y873000I-457J-670D01*
G01Y871600D01*
G02X431978Y870788I-812J0D01*
G37*
G36*
G01X463478Y807288D02*
X462078D01*
G02X461266Y808100I0J812D01*
G01Y809500D01*
G02X461620Y810170I811J0D01*
G03Y810830I-226J330D01*
G02X461266Y811500I457J670D01*
G01Y812900D01*
G02X462078Y813712I812J0D01*
G01X463478D01*
G02X464290Y812900I0J-812D01*
G01Y811500D01*
G02X463936Y810830I-811J0D01*
G03Y810170I226J-330D01*
G02X464290Y809500I-457J-670D01*
G01Y808100D01*
G02X463478Y807288I-812J0D01*
G37*
G36*
G01X456978D02*
X455578D01*
G02X454766Y808100I0J812D01*
G01Y809500D01*
G02X455120Y810170I811J0D01*
G03Y810830I-226J330D01*
G02X454766Y811500I457J670D01*
G01Y812900D01*
G02X455578Y813712I812J0D01*
G01X456978D01*
G02X457790Y812900I0J-812D01*
G01Y811500D01*
G02X457436Y810830I-811J0D01*
G03Y810170I226J-330D01*
G02X457790Y809500I-457J-670D01*
G01Y808100D01*
G02X456978Y807288I-812J0D01*
G37*
G36*
G01X432478D02*
X431078D01*
G02X430266Y808100I0J812D01*
G01Y809500D01*
G02X430620Y810170I811J0D01*
G03Y810830I-226J330D01*
G02X430266Y811500I457J670D01*
G01Y812900D01*
G02X431078Y813712I812J0D01*
G01X432478D01*
G02X433290Y812900I0J-812D01*
G01Y811500D01*
G02X432936Y810830I-811J0D01*
G03Y810170I226J-330D01*
G02X433290Y809500I-457J-670D01*
G01Y808100D01*
G02X432478Y807288I-812J0D01*
G37*
G36*
G01X425978D02*
X424578D01*
G02X423766Y808100I0J812D01*
G01Y809500D01*
G02X424120Y810170I811J0D01*
G03Y810830I-226J330D01*
G02X423766Y811500I457J670D01*
G01Y812900D01*
G02X424578Y813712I812J0D01*
G01X425978D01*
G02X426790Y812900I0J-812D01*
G01Y811500D01*
G02X426436Y810830I-811J0D01*
G03Y810170I226J-330D01*
G02X426790Y809500I-457J-670D01*
G01Y808100D01*
G02X425978Y807288I-812J0D01*
G37*
G36*
G01X72776Y391868D02*
X71176D01*
G02X70364Y392679I-1J811D01*
G01Y394279D01*
G02X70718Y394949I811J0D01*
G03Y395609I-226J330D01*
G02X70364Y396279I457J670D01*
G01Y397879D01*
G02X71176Y398690I812J-1D01*
G01X72776D01*
G02X73412Y398383I0J-812D01*
G03X74040I314J248D01*
G02X74676Y398690I636J-505D01*
G01X76276D01*
G02X77088Y397879I1J-811D01*
G01Y396279D01*
G02X76734Y395609I-811J0D01*
G03Y394949I226J-330D01*
G02X77088Y394279I-457J-670D01*
G01Y392679D01*
G02X76276Y391868I-812J1D01*
G01X74676D01*
G02X74040Y392175I0J812D01*
G03X73412I-314J-248D01*
G02X72776Y391868I-636J505D01*
G37*
G36*
G01X63776D02*
X62176D01*
G02X61364Y392679I-1J811D01*
G01Y394279D01*
G02X61718Y394949I811J0D01*
G03Y395609I-226J330D01*
G02X61364Y396279I457J670D01*
G01Y397879D01*
G02X62176Y398690I812J-1D01*
G01X63776D01*
G02X64412Y398383I0J-812D01*
G03X65040I314J248D01*
G02X65676Y398690I636J-505D01*
G01X67276D01*
G02X68088Y397879I1J-811D01*
G01Y396279D01*
G02X67734Y395609I-811J0D01*
G03Y394949I226J-330D01*
G02X68088Y394279I-457J-670D01*
G01Y392679D01*
G02X67276Y391868I-812J1D01*
G01X65676D01*
G02X65040Y392175I0J812D01*
G03X64412I-314J-248D01*
G02X63776Y391868I-636J505D01*
G37*
G36*
G01X54276D02*
X52676D01*
G02X51864Y392679I-1J811D01*
G01Y394279D01*
G02X52218Y394949I811J0D01*
G03Y395609I-226J330D01*
G02X51864Y396279I457J670D01*
G01Y397879D01*
G02X52676Y398690I812J-1D01*
G01X54276D01*
G02X54912Y398383I0J-812D01*
G03X55540I314J248D01*
G02X56176Y398690I636J-505D01*
G01X57776D01*
G02X58588Y397879I1J-811D01*
G01Y396279D01*
G02X58234Y395609I-811J0D01*
G03Y394949I226J-330D01*
G02X58588Y394279I-457J-670D01*
G01Y392679D01*
G02X57776Y391868I-812J1D01*
G01X56176D01*
G02X55540Y392175I0J812D01*
G03X54912I-314J-248D01*
G02X54276Y391868I-636J505D01*
G37*
G36*
G01X44776D02*
X43176D01*
G02X42364Y392679I-1J811D01*
G01Y394279D01*
G02X42718Y394949I811J0D01*
G03Y395609I-226J330D01*
G02X42364Y396279I457J670D01*
G01Y397879D01*
G02X43176Y398690I812J-1D01*
G01X44776D01*
G02X45412Y398383I0J-812D01*
G03X46040I314J248D01*
G02X46676Y398690I636J-505D01*
G01X48276D01*
G02X49088Y397879I1J-811D01*
G01Y396279D01*
G02X48734Y395609I-811J0D01*
G03Y394949I226J-330D01*
G02X49088Y394279I-457J-670D01*
G01Y392679D01*
G02X48276Y391868I-812J1D01*
G01X46676D01*
G02X46040Y392175I0J812D01*
G03X45412I-314J-248D01*
G02X44776Y391868I-636J505D01*
G37*
G36*
G01X488233Y320083D02*
G02X487071Y317098I-621J-1477D01*
G01X487040Y317109D01*
X484435Y317176D01*
X484403Y317166D01*
G02X483299Y319951I-448J1434D01*
G03X483309Y320666I-174J360D01*
G02X484502Y323416I691J1334D01*
G01X484532Y323405D01*
X486713Y323336D01*
X486743Y323344D01*
G02X488128Y320756I412J-1444D01*
G03X488233Y320083I260J-304D01*
G37*
G36*
G01X180095Y302298D02*
X178495D01*
G02X177684Y303109I0J811D01*
G01Y304709D01*
G02X178037Y305379I812J0D01*
G03Y306039I-226J330D01*
G02X177684Y306709I459J670D01*
G01Y308309D01*
G02X178495Y309120I811J0D01*
G01X180095D01*
G02X180906Y308309I0J-811D01*
G01Y306709D01*
G02X180553Y306039I-812J0D01*
G03Y305379I226J-330D01*
G02X180906Y304709I-459J-670D01*
G01Y303109D01*
G02X180095Y302298I-811J0D01*
G37*
G36*
G01X176095D02*
X174495D01*
G02X173684Y303109I0J811D01*
G01Y304709D01*
G02X174037Y305379I812J0D01*
G03Y306039I-226J330D01*
G02X173684Y306709I459J670D01*
G01Y308309D01*
G02X174495Y309120I811J0D01*
G01X176095D01*
G02X176906Y308309I0J-811D01*
G01Y306709D01*
G02X176553Y306039I-812J0D01*
G03Y305379I226J-330D01*
G02X176906Y304709I-459J-670D01*
G01Y303109D01*
G02X176095Y302298I-811J0D01*
G37*
G36*
G01X170595D02*
X168995D01*
G02X168184Y303109I0J811D01*
G01Y304709D01*
G02X168537Y305379I812J0D01*
G03Y306039I-226J330D01*
G02X168184Y306709I459J670D01*
G01Y308309D01*
G02X168995Y309120I811J0D01*
G01X170595D01*
G02X171406Y308309I0J-811D01*
G01Y306709D01*
G02X171053Y306039I-812J0D01*
G03Y305379I226J-330D01*
G02X171406Y304709I-459J-670D01*
G01Y303109D01*
G02X170595Y302298I-811J0D01*
G37*
G36*
G01X166595D02*
X164995D01*
G02X164184Y303109I0J811D01*
G01Y304709D01*
G02X164537Y305379I812J0D01*
G03Y306039I-226J330D01*
G02X164184Y306709I459J670D01*
G01Y308309D01*
G02X164995Y309120I811J0D01*
G01X166595D01*
G02X167406Y308309I0J-811D01*
G01Y306709D01*
G02X167053Y306039I-812J0D01*
G03Y305379I226J-330D01*
G02X167406Y304709I-459J-670D01*
G01Y303109D01*
G02X166595Y302298I-811J0D01*
G37*
G36*
G01X214595Y298798D02*
X212995D01*
G02X212184Y299609I0J811D01*
G01Y301209D01*
G02X212537Y301879I812J0D01*
G03Y302539I-226J330D01*
G02X212184Y303209I459J670D01*
G01Y304809D01*
G02X212995Y305620I811J0D01*
G01X214595D01*
G02X215406Y304809I0J-811D01*
G01Y303209D01*
G02X215053Y302539I-812J0D01*
G03Y301879I226J-330D01*
G02X215406Y301209I-459J-670D01*
G01Y299609D01*
G02X214595Y298798I-811J0D01*
G37*
G36*
G01X210595D02*
X208995D01*
G02X208184Y299609I0J811D01*
G01Y301209D01*
G02X208537Y301879I812J0D01*
G03Y302539I-226J330D01*
G02X208184Y303209I459J670D01*
G01Y304809D01*
G02X208995Y305620I811J0D01*
G01X210595D01*
G02X211406Y304809I0J-811D01*
G01Y303209D01*
G02X211053Y302539I-812J0D01*
G03Y301879I226J-330D01*
G02X211406Y301209I-459J-670D01*
G01Y299609D01*
G02X210595Y298798I-811J0D01*
G37*
G36*
G01X201095D02*
X199495D01*
G02X198684Y299609I0J811D01*
G01Y301209D01*
G02X199037Y301879I812J0D01*
G03Y302539I-226J330D01*
G02X198684Y303209I459J670D01*
G01Y304809D01*
G02X199495Y305620I811J0D01*
G01X201095D01*
G02X201731Y305313I0J-812D01*
G03X202359I314J248D01*
G02X202995Y305620I636J-505D01*
G01X204595D01*
G02X205406Y304809I0J-811D01*
G01Y303209D01*
G02X205053Y302539I-812J0D01*
G03Y301879I226J-330D01*
G02X205406Y301209I-459J-670D01*
G01Y299609D01*
G02X204595Y298798I-811J0D01*
G01X202995D01*
G02X202359Y299105I0J812D01*
G03X201731I-314J-248D01*
G02X201095Y298798I-636J505D01*
G37*
G36*
G01X373190Y139908D02*
X373194Y142009D01*
X373184Y142040D01*
G02X375851Y143362I1423J480D01*
G03X376513I331J224D01*
G02X379178Y142034I1244J-842D01*
G01X379167Y142002D01*
X379163Y139911D01*
X379173Y139880D01*
G02X376509Y138554I-1423J-480D01*
G03X375846Y138552I-331J-225D01*
G02X373179Y139876I-1246J839D01*
G01X373190Y139908D01*
G37*
G36*
G01X385266Y138533D02*
G02X382603Y139871I-1247J838D01*
G01X382614Y139902D01*
X382638Y142022D01*
X382628Y142054D01*
G02X385300Y143362I1428J466D01*
G03X385962I331J224D01*
G02X388623Y142022I1244J-842D01*
G01X388612Y141991D01*
X388590Y139875D01*
X388600Y139844D01*
G02X385929Y138534I-1427J-468D01*
G03X385266Y138533I-331J-224D01*
G37*
G36*
G01X401542Y139885D02*
Y142006D01*
X401532Y142037D01*
G02X404197Y143363I1422J483D01*
G03X404860I331J224D01*
G02X407525Y142037I1243J-843D01*
G01X407514Y142005D01*
Y139886D01*
X407525Y139854D01*
G02X404859Y138529I-1422J-483D01*
G03X404197Y138528I-331J-225D01*
G02X401531Y139854I-1244J842D01*
G01X401542Y139885D01*
G37*
G36*
G01X394769Y138520D02*
G02X392087Y139821I-1259J819D01*
G01X392098Y139852D01*
X392094Y142003D01*
X392084Y142035D01*
G02X394749Y143362I1421J485D01*
G03X395411I331J224D01*
G02X398081Y142050I1243J-842D01*
G01X398071Y142018D01*
X398090Y139889D01*
X398101Y139858D01*
G02X395436Y138525I-1418J-496D01*
G03X394769Y138520I-332J-223D01*
G37*
G36*
G01X369741Y151443D02*
X369744Y149343D01*
X369755Y149312D01*
G02X369398Y147768I-1422J-485D01*
G03X369680Y147086I284J-282D01*
G01X370984Y147081D01*
X371016Y147091D01*
G02X371004Y144247I477J-1424D01*
G01X370973Y144258D01*
X369647Y144263D01*
G03X369366Y143577I-1J-400D01*
G02X369735Y142018I-1052J-1072D01*
G01X369724Y141986D01*
X369718Y139911D01*
X369729Y139880D01*
G02X369360Y138332I-1424J-479D01*
G03X369637Y137647I281J-285D01*
G01X370953Y137637D01*
X370984Y137647D01*
G02X370962Y134803I472J-1426D01*
G01X370930Y134814D01*
X368799Y134830D01*
X368768Y134820D01*
G02X367460Y137494I-472J1426D01*
G03X367462Y138158I-222J333D01*
G02X366884Y139888I843J1243D01*
G01X366895Y139920D01*
X366901Y141995D01*
X366890Y142026D01*
G02X367487Y143759I1424J479D01*
G03Y144426I-221J334D01*
G02X367478Y146928I827J1254D01*
G03X367482Y147589I-223J332D01*
G02X366910Y149308I851J1238D01*
G01X366921Y149340D01*
X366918Y151440D01*
X366907Y151471D01*
G02X367260Y153011I1422J485D01*
G03X366975Y153693I-284J282D01*
G01X365658Y153690D01*
X365626Y153679D01*
G02X365620Y156523I-486J1421D01*
G01X365651Y156513D01*
X366935Y156515D01*
G03X367215Y157200I-1J400D01*
G02X366857Y158776I1056J1068D01*
G01X366869Y158807D01*
X366905Y160911D01*
X366895Y160942D01*
G02X367276Y162474I1431J458D01*
G03X366993Y163160I-279J286D01*
G01X365686Y163148D01*
X365655Y163137D01*
G02X365627Y165981I-497J1417D01*
G01X365659Y165971D01*
X366971Y165983D01*
G03X367255Y166661I-4J400D01*
G02X366908Y168178I1079J1045D01*
G01X366918Y168209D01*
X366902Y170304D01*
X366891Y170336D01*
G02X369735Y170358I1418J494D01*
G01X369725Y170327D01*
X369741Y168232D01*
X369752Y168201D01*
G02X369189Y166471I-1418J-495D01*
G03X369187Y165815I228J-329D01*
G02X369147Y163328I-862J-1230D01*
G03Y162658I218J-335D01*
G02X369740Y160892I-821J-1258D01*
G01X369728Y160861D01*
X369692Y158757D01*
X369702Y158726D01*
G02X369131Y157036I-1431J-458D01*
G03X369144Y156372I229J-328D01*
G02X369173Y153862I-811J-1265D01*
G03X369172Y153199I223J-332D01*
G02X369752Y151475I-843J-1243D01*
G01X369741Y151443D01*
G37*
G54D61*
X1272441Y7087D03*
X1299213D03*
G54D59*
X1224016Y180709D03*
G54D58*
X945197Y380000D03*
X968819D03*
G54D62*
X1379862Y108465D03*
Y119095D03*
G54D60*
X1224016Y386221D03*
G54D53*
X35435Y373228D03*
X82675D03*
G54D52*
X21220D03*
X96890D03*
X157480Y283071D03*
X220472D03*
G54D63*
X402953Y23622D03*
X413189D03*
X423425D03*
G54D50*
X1227165Y411417D03*
X1227166Y155511D03*
X1008268Y411417D03*
G54D51*
Y244094D03*
G54D54*
X270078Y92125D03*
Y155117D03*
X743897Y353543D03*
Y410629D03*
X1305117Y87548D03*
Y262745D03*
X1376968Y147243D03*
Y216535D03*
X490944Y255118D03*
Y79921D03*
G54D57*
X600925Y44134D03*
X638917D03*
G54D56*
X537994Y303150D03*
X825984D03*
G54D55*
X332086Y408858D03*
X355708Y96456D03*
X450196Y257874D03*
X572243Y337992D03*
G54D17*
X50000Y659500D03*
X58804Y699720D03*
X109000Y844220D03*
X111000Y981500D03*
X124500Y515500D03*
X128000Y544050D03*
X121200Y584278D03*
X166200Y506500D03*
X172000Y486400D03*
X182000Y577500D03*
X176938Y680465D03*
X182500Y677500D03*
X234000Y562000D03*
X236500Y574000D03*
X238500Y705000D03*
X253500Y707250D03*
X294500Y98500D03*
X313402Y156000D03*
X306155Y497700D03*
X331040Y152601D03*
X330929Y148600D03*
X317248Y156000D03*
X320338Y507683D03*
X347000Y120040D03*
X340000D03*
X344055Y529000D03*
X340055Y524000D03*
X342971Y525750D03*
X339000Y878500D03*
X336000Y871500D03*
X339000Y894000D03*
Y885500D03*
X337300Y949500D03*
X353740Y133300D03*
X352040Y143000D03*
X349829Y153400D03*
X355084Y172441D03*
X351929Y162200D03*
X362036Y177155D03*
X358858Y177128D03*
X358848Y174010D03*
X358879Y192929D03*
X351320Y194520D03*
X361987Y189747D03*
X358850Y196050D03*
X355090Y195660D03*
X355139Y190099D03*
X351731Y190274D03*
X362500Y286000D03*
X361155Y496203D03*
X356555Y513000D03*
X357055Y507000D03*
X356055Y502000D03*
X368296Y136246D03*
X371456Y136221D03*
X368305Y139401D03*
X371482Y133058D03*
X365133Y129133D03*
X374600Y139390D03*
X377750Y139400D03*
X368333Y155107D03*
X365140Y155100D03*
X377757Y145670D03*
X368333Y148827D03*
X368329Y151956D03*
X371493Y145667D03*
X368314Y142505D03*
Y145680D03*
X371457Y155080D03*
X377759Y152000D03*
X365146Y151942D03*
X365182Y142532D03*
X374607Y142520D03*
X377757D03*
X368309Y170830D03*
X368334Y167706D03*
X365158Y164554D03*
X368325Y164585D03*
X368326Y161400D03*
X368271Y158268D03*
X374582Y161404D03*
X374577Y164559D03*
X377750Y170846D03*
X374570Y158267D03*
X365176Y161400D03*
X365187Y186605D03*
X368308Y177202D03*
X374560Y177210D03*
X371485Y177175D03*
X368307Y205511D03*
Y199211D03*
X368336Y192904D03*
X374606Y189763D03*
Y192912D03*
X377756Y211810D03*
X365158D03*
X371457D03*
X367665Y363430D03*
X368055Y380500D03*
X368555Y385000D03*
Y376500D03*
Y389000D03*
X368165Y393402D03*
X370500Y518000D03*
X379500Y963500D03*
X390355Y139371D03*
X380920Y139370D03*
X387173Y139376D03*
X392240Y129000D03*
X383680Y129030D03*
X396683Y139362D03*
X393510Y139340D03*
X384019Y139371D03*
X384056Y145670D03*
X390355D03*
X396655D03*
X387206Y142520D03*
X384056D03*
X390339Y151990D03*
X396639D03*
X380888Y148799D03*
X396655Y142520D03*
X393505D03*
X387205Y167715D03*
X384041Y170888D03*
X380928Y167701D03*
X393528Y167702D03*
X384030Y177120D03*
X393542Y186614D03*
X393490Y174039D03*
X393541Y180315D03*
X384036Y189747D03*
X393519Y192900D03*
X387209Y192930D03*
X384055Y211810D03*
X393504Y218109D03*
X395500Y237000D03*
X389500Y319150D03*
X392589Y317729D03*
X394055Y335000D03*
X391325Y324520D03*
X386755Y326100D03*
X384160Y328812D03*
X391555Y338350D03*
X393061Y346800D03*
X393755Y350500D03*
X390230Y349327D03*
X396055Y338000D03*
X395855Y366890D03*
X392991Y365797D03*
X391628Y358852D03*
X394915Y359725D03*
X387515Y365500D03*
X387265Y384370D03*
X394935Y385150D03*
X382803Y385207D03*
X391215Y384900D03*
X396490Y388597D03*
X388500Y400575D03*
X390543Y391950D03*
X387000Y404275D03*
X388750Y951750D03*
X387061Y986061D03*
X389500Y992000D03*
X399783Y136237D03*
X402953Y139370D03*
X402800Y129180D03*
X406103Y139371D03*
X406110Y145660D03*
X402954Y145670D03*
Y142520D03*
X406103D03*
X402938Y151950D03*
X399827Y167702D03*
X406140Y167716D03*
X406127Y161404D03*
X412427D03*
X412426Y167703D03*
X399841Y186614D03*
X399840Y180315D03*
X399790Y174039D03*
X406126Y174003D03*
X406139Y180315D03*
X406101Y186613D03*
X412426Y174003D03*
X412439Y186614D03*
X412400Y180314D03*
X406128Y192901D03*
X399791Y192938D03*
X412428Y192901D03*
X399803Y211810D03*
X406102D03*
X406099Y214950D03*
X409249Y214965D03*
X412767Y233162D03*
X400000Y237500D03*
X409500Y271500D03*
X404920Y334054D03*
X412794D03*
X408857D03*
X400983D03*
X397983Y333998D03*
X408857Y330117D03*
X400523Y325283D03*
X412794Y341928D03*
X397555Y345146D03*
X398055Y350296D03*
X398555Y339283D03*
X408857Y345865D03*
X404965Y342120D03*
X412794Y337991D03*
X400055Y343146D03*
X412794Y365550D03*
Y357676D03*
X397117Y364138D03*
X412794Y353739D03*
X404920Y369487D03*
X412794Y361613D03*
X408925Y361680D03*
X400395Y362450D03*
X400885Y354120D03*
X404935Y353840D03*
X412794Y369487D03*
X408857D03*
Y353739D03*
X412794Y377363D03*
Y385237D03*
Y381300D03*
X399923Y372000D03*
X412794Y400985D03*
Y393111D03*
X408857Y389174D03*
X400983Y400985D03*
X404920Y397048D03*
Y400985D03*
Y389174D03*
X412794Y397048D03*
Y389174D03*
X408857Y397048D03*
X400983D03*
X404920Y393111D03*
X412794Y416733D03*
Y408859D03*
X400983Y404922D03*
X412794Y412796D03*
X404920Y404922D03*
X408857D03*
Y412796D03*
X412794Y404922D03*
X404920Y416733D03*
X400983D03*
X412794Y424607D03*
X408857Y420670D03*
X412794D03*
X404555Y430500D03*
X404920Y420670D03*
X406555Y428300D03*
X399555Y438500D03*
X428375Y119735D03*
X418940Y125000D03*
X415552Y136221D03*
X421590Y128500D03*
X418702Y136221D03*
X413540Y128500D03*
X425000Y136220D03*
X428116Y136218D03*
X421851Y136221D03*
X423686Y126215D03*
X421851Y142520D03*
X415552D03*
X428151D03*
X418700Y148818D03*
X428149D03*
X415551D03*
X424999D03*
X421850D03*
X428149Y161416D03*
X418726Y167703D03*
Y174003D03*
Y180303D03*
X418701Y186614D03*
X424999Y192912D03*
X418727Y192902D03*
X428150Y211810D03*
X415551D03*
X421850D03*
X428172Y221320D03*
X424979Y218127D03*
X428047Y218049D03*
X415551Y218109D03*
X418729Y218100D03*
X421850Y218109D03*
X418729Y221268D03*
X420500Y234500D03*
X422630Y227232D03*
X426147Y230982D03*
X420714Y225190D03*
X429444Y230192D03*
X419000Y227405D03*
X427965Y318293D03*
X419913Y318051D03*
X417650Y316400D03*
X416482Y319022D03*
X424555Y318000D03*
X420668Y334054D03*
X428542D03*
X424023Y320783D03*
X424605Y334054D03*
Y330117D03*
X416731D03*
X416950Y321783D03*
X416731Y334054D03*
X420668Y337991D03*
X428542Y345865D03*
X416615Y349930D03*
X428542Y349802D03*
Y341928D03*
X424605Y337991D03*
X428542D03*
X420668Y341928D03*
X424605Y349802D03*
X420668D03*
X416731Y337991D03*
X420668Y345865D03*
X416731Y341928D03*
X424605D03*
X428542Y361613D03*
Y369487D03*
Y353739D03*
X416731D03*
X420668Y357676D03*
X428542Y365550D03*
X416731Y369487D03*
X420668Y353739D03*
X416731Y365550D03*
X424605D03*
X420668D03*
X416731Y361613D03*
X420668Y369487D03*
X424605Y357676D03*
X420668Y361613D03*
X416555Y357500D03*
X428542Y357676D03*
Y385237D03*
Y381300D03*
X428500Y377000D03*
X416731Y381300D03*
Y377363D03*
X428445Y373550D03*
X420668Y377363D03*
Y385237D03*
X416731D03*
X424605Y381300D03*
X420668D03*
X416731Y389174D03*
X428555Y393000D03*
X420668Y389174D03*
X416731Y393111D03*
Y397048D03*
X420668Y393111D03*
X424605Y397048D03*
X428542Y389174D03*
X420668Y397048D03*
X416731Y400985D03*
X424605Y389174D03*
Y404922D03*
Y408859D03*
X420668Y404922D03*
X428542Y408859D03*
X420668D03*
X428542Y404922D03*
X416731Y412796D03*
X424605D03*
X432540Y123000D03*
X435640D03*
X437599Y136221D03*
X434450D03*
X439540Y124500D03*
X431407Y136285D03*
X440931Y129061D03*
X431348Y125911D03*
X442323Y126000D03*
X437945Y127159D03*
X437598Y148818D03*
Y155118D03*
X434450Y142520D03*
X440765Y145670D03*
X443928Y148811D03*
X443891Y151999D03*
X443890Y142565D03*
X443909Y145650D03*
X443936Y155118D03*
X437598Y167716D03*
Y161417D03*
X443899Y161430D03*
X443882Y167737D03*
X443899Y164530D03*
X443871Y158278D03*
X437598Y174015D03*
Y180314D03*
Y186614D03*
X443910Y174041D03*
X443879Y180320D03*
X443887Y177138D03*
X440769Y183480D03*
X443919D03*
X437598Y205511D03*
Y199212D03*
Y192913D03*
X443897Y205512D03*
Y192914D03*
X443898Y199212D03*
X443897Y202363D03*
Y196063D03*
X437598Y211810D03*
X443897Y211811D03*
Y208662D03*
X431336Y218111D03*
X434448Y218109D03*
X437598D03*
X436529Y229500D03*
X434334Y226789D03*
X443113Y226339D03*
X439980Y232126D03*
X441379Y229700D03*
X432307Y224857D03*
X437112Y232239D03*
X445892Y225995D03*
X438500Y250000D03*
X431023Y317283D03*
X440353Y330117D03*
X434448Y320783D03*
X440353Y334054D03*
X432523Y330283D03*
X444555Y334000D03*
X441335Y321000D03*
X436416Y334054D03*
X432585Y345850D03*
X444290Y341928D03*
X432365Y341880D03*
X444290Y337991D03*
X432605Y337880D03*
X444290Y345865D03*
X440353D03*
X440555Y338000D03*
X444290Y369487D03*
X436416D03*
X440353Y357676D03*
X444290Y353739D03*
X440353Y365550D03*
X436416Y353739D03*
Y361613D03*
X432479Y381300D03*
X444290D03*
X440353Y377363D03*
X436416Y381300D03*
X444290Y397048D03*
X440353D03*
X436416D03*
X444290Y400985D03*
X436416D03*
X444290Y389174D03*
X436416D03*
X432479Y408859D03*
Y404922D03*
X436416D03*
Y408859D03*
X444290Y404922D03*
Y408859D03*
X440353D03*
Y404922D03*
Y412796D03*
X432479D03*
X448669Y126510D03*
X450209Y129230D03*
X447389Y129580D03*
X454676Y137495D03*
X456429Y135000D03*
X457929Y132500D03*
X451679Y148250D03*
X461685Y150386D03*
X455731Y154302D03*
X460300Y141100D03*
X454929Y146500D03*
X453929Y140334D03*
X459069Y151980D03*
X451329Y165570D03*
X453599Y156693D03*
X450196Y189764D03*
X454329Y199800D03*
X452929Y203900D03*
X452329Y194300D03*
X447063Y199234D03*
X447047Y189764D03*
X451292Y197637D03*
X456479Y202400D03*
X455929Y192800D03*
X456229Y196700D03*
X453829Y215600D03*
X453729Y219300D03*
X452393Y210236D03*
X458029Y213469D03*
X457798Y217769D03*
X457729Y206800D03*
X448840Y225775D03*
X455429Y227500D03*
X451929Y229800D03*
X456929Y224507D03*
X460040Y330117D03*
X448227D03*
X452223Y333983D03*
X448227Y334054D03*
X460040D03*
X456103D03*
Y341928D03*
X460040Y337991D03*
X455825Y349840D03*
X448000Y346000D03*
X456055Y338000D03*
X452055D03*
X452165Y349470D03*
X456103Y369487D03*
Y353739D03*
Y361613D03*
X460040Y357676D03*
Y365550D03*
X448227D03*
Y357676D03*
X460040Y385237D03*
X456103Y381300D03*
X460040Y377363D03*
X448227Y385237D03*
Y377363D03*
X456103Y397048D03*
X448227D03*
X456103Y389174D03*
X456223Y404883D03*
Y408783D03*
X452123Y416783D03*
X460040Y412796D03*
X448227D03*
X452223Y404883D03*
X448227Y408859D03*
X452223Y408783D03*
X448227Y404922D03*
X471480Y105660D03*
X466464Y151000D03*
X466500Y144500D03*
X463969Y147610D03*
X469429Y172500D03*
Y165590D03*
X473131Y169131D03*
X477429Y162500D03*
X469429Y179500D03*
X464570Y215750D03*
X467300Y320100D03*
X467914Y330117D03*
X463977Y334054D03*
X467914D03*
X475788Y330117D03*
X463977Y341928D03*
X471851Y337991D03*
X467914D03*
X463977D03*
X471851Y349802D03*
X467914Y345865D03*
X471851Y361613D03*
Y369487D03*
Y353739D03*
Y357676D03*
X463977Y369487D03*
Y361613D03*
X471851Y377363D03*
Y381300D03*
X463977D03*
Y400985D03*
X471851D03*
Y389174D03*
X463977D03*
Y408859D03*
Y404922D03*
X467914Y408859D03*
Y404922D03*
X475788Y412796D03*
X471851Y416733D03*
X467914Y412796D03*
X480500Y181800D03*
X483955Y318600D03*
X487500Y333833D03*
X483662Y334054D03*
X487599Y330117D03*
X483662Y326180D03*
X484000Y322000D03*
X487599Y326180D03*
X487155Y321900D03*
X483662Y330117D03*
X487599Y337991D03*
X483662D03*
Y341928D03*
X487599D03*
X483662Y345865D03*
X487599Y349802D03*
X483662D03*
X487599Y345865D03*
X479725Y341928D03*
Y349802D03*
X487603Y369483D03*
X483662Y357676D03*
X487599D03*
X483663Y365463D03*
X483662Y361613D03*
Y353739D03*
X487599D03*
X483683Y369403D03*
X491536Y369487D03*
Y361613D03*
X479725Y365550D03*
Y357676D03*
X491536Y381300D03*
X479725Y385237D03*
Y377363D03*
X491536Y397048D03*
Y389174D03*
X479725Y400985D03*
Y393111D03*
X491536Y412796D03*
Y404922D03*
X483662Y412796D03*
Y404922D03*
X479725Y416733D03*
X487599Y420670D03*
X495473Y334054D03*
Y341928D03*
Y385237D03*
Y377363D03*
Y400985D03*
Y393111D03*
X521700Y114000D03*
X533441Y211775D03*
X559750Y264500D03*
X605000Y209500D03*
X604500Y227500D03*
Y223000D03*
X599000Y804000D03*
X622500Y696500D03*
X625000Y706000D03*
X632500Y530000D03*
X691400Y231100D03*
X710100Y182700D03*
X780000Y250000D03*
X862500Y65000D03*
X865000Y488500D03*
X874000Y56000D03*
X873500Y61500D03*
X884500Y323500D03*
X881000Y736500D03*
X945000Y141500D03*
X947500Y153000D03*
X959900Y180700D03*
X974500Y188500D03*
X975007Y194300D03*
X1002500Y653000D03*
X1001100Y776500D03*
X1015000Y477500D03*
X1011500Y667500D03*
X1022000Y492500D03*
X1022500Y637500D03*
X1027504Y853366D03*
X1045000Y266600D03*
X1041410Y695394D03*
Y690694D03*
Y699834D03*
X1055000Y214500D03*
X1055500Y360000D03*
X1062940Y629945D03*
X1065978Y664568D03*
X1063056Y681554D03*
X1062700Y672600D03*
X1054080Y680630D03*
X1084500Y223500D03*
X1074000Y660500D03*
X1074500Y665500D03*
X1088000Y461000D03*
X1103300Y492000D03*
X1114500Y645000D03*
X1118630Y714820D03*
X1116550Y783600D03*
X1119060Y791083D03*
X1132500Y333000D03*
X1126500Y614500D03*
X1132423Y663902D03*
X1135553Y663957D03*
X1132440Y676555D03*
X1129272Y673350D03*
X1129271Y670275D03*
X1126102Y676518D03*
X1132402Y673405D03*
X1132398Y667102D03*
X1129290Y676555D03*
X1126121Y679722D03*
X1132421Y679648D03*
X1132395Y670225D03*
X1126117Y685952D03*
X1129273Y689170D03*
X1126122Y689171D03*
X1129290Y692303D03*
X1126116Y692279D03*
X1132423Y695469D03*
X1132440Y692265D03*
Y686004D03*
X1132434Y682860D03*
X1129278Y682804D03*
X1129289Y686005D03*
X1126157Y695435D03*
X1129238Y704878D03*
X1132440Y701714D03*
X1129270D03*
X1126121Y711218D03*
X1129285Y708056D03*
X1126114Y701703D03*
X1126093Y704874D03*
X1132406Y704904D03*
X1132440Y698564D03*
X1129290D03*
X1126155Y708029D03*
X1132445Y714345D03*
X1129260Y714350D03*
X1126121Y714368D03*
X1132417Y711189D03*
X1129277Y711210D03*
X1128959Y729952D03*
X1126969Y727981D03*
X1132459Y717481D03*
X1127183Y740805D03*
X1126671Y744629D03*
X1126885Y736721D03*
X1123393Y743726D03*
X1124497Y734140D03*
X1124326Y738960D03*
X1126955Y731909D03*
X1124978Y747578D03*
X1130900Y766700D03*
X1124460Y768140D03*
X1125900Y764200D03*
X1129501Y776929D03*
X1120400Y781600D03*
X1126360Y792640D03*
X1127160Y788837D03*
X1129497Y792673D03*
X1130610Y788820D03*
X1134145Y788450D03*
X1132684Y792636D03*
X1124360Y788390D03*
X1132600Y784822D03*
X1120529Y786350D03*
X1123254Y792663D03*
X1131095Y799965D03*
X1124796Y800150D03*
X1144425Y325500D03*
X1143000Y629000D03*
X1138757Y663937D03*
X1151354Y663936D03*
X1148150Y663956D03*
X1141900Y663944D03*
X1148188Y667106D03*
Y670256D03*
X1151282Y667088D03*
X1141600Y673590D03*
X1141954Y676581D03*
X1135589Y673368D03*
X1144983Y667085D03*
X1145020Y670200D03*
X1136150Y676500D03*
X1135685Y679613D03*
X1135598Y667080D03*
X1135595Y670225D03*
X1141868Y670273D03*
X1138708Y667113D03*
X1139245Y675106D03*
X1135589Y682854D03*
Y695415D03*
X1139858Y692074D03*
X1139000Y685667D03*
X1144880Y707720D03*
X1145000Y711200D03*
X1138729Y714360D03*
X1151307Y714306D03*
X1141765Y711030D03*
X1145053Y714327D03*
X1148169Y711219D03*
X1141840Y714339D03*
X1138320Y710066D03*
X1135589Y701714D03*
X1151352Y711178D03*
X1140710Y707750D03*
X1138400Y705300D03*
X1136304Y707482D03*
X1151318Y717518D03*
X1148135Y720634D03*
X1138685Y720633D03*
X1141870Y717518D03*
X1148167Y717517D03*
X1138730Y717480D03*
X1141904Y720633D03*
X1150734Y736950D03*
X1149470Y734451D03*
X1137030Y745300D03*
X1146370Y769310D03*
X1142095Y773774D03*
X1151564Y776924D03*
X1146200Y766300D03*
X1142323Y780250D03*
X1138961Y776940D03*
X1150310Y783840D03*
X1142120Y795830D03*
X1145270D03*
X1138970D03*
X1145270Y792670D03*
X1141700Y785113D03*
X1138545Y787952D03*
X1145740Y789140D03*
X1138931Y792658D03*
X1142086Y789513D03*
X1136236Y782142D03*
X1151590Y792660D03*
X1143470Y782805D03*
X1141100Y831600D03*
X1157599Y663956D03*
X1167098Y663932D03*
X1160748Y660807D03*
Y657657D03*
X1160741Y663949D03*
X1163946Y663946D03*
X1157613Y673418D03*
X1167692Y674996D03*
X1160768Y676535D03*
X1154470Y673363D03*
X1152090Y677010D03*
X1163917Y670275D03*
X1160741Y667099D03*
X1163914Y673352D03*
X1167034Y667092D03*
X1157655Y667087D03*
X1160770Y673421D03*
X1163944Y667076D03*
X1154487Y670256D03*
X1157670Y707960D03*
X1167048Y714312D03*
X1163968Y708000D03*
X1154434Y714335D03*
X1157581Y714331D03*
X1163905Y711206D03*
X1157636Y711200D03*
X1167103Y711107D03*
X1167000Y727500D03*
X1157637Y717463D03*
X1157643Y720642D03*
X1152248Y730404D03*
X1154430Y717481D03*
X1152400Y727600D03*
X1167049Y717501D03*
X1167048Y720612D03*
X1163898Y717462D03*
Y720612D03*
X1157112Y731702D03*
X1164200Y744500D03*
X1157000Y734500D03*
X1163830Y747899D03*
X1158100Y769700D03*
X1162450Y769190D03*
X1167002Y767508D03*
X1167326Y776936D03*
X1161051Y792660D03*
X1164196Y795814D03*
X1153219Y781303D03*
X1161545Y788844D03*
X1162693Y780865D03*
X1158092Y787715D03*
X1154712Y792690D03*
X1165492Y780957D03*
X1154200Y788900D03*
X1154700Y795790D03*
X1161022Y785693D03*
X1165063Y787500D03*
X1167410Y785530D03*
X1154800Y799000D03*
X1173332Y663938D03*
X1176506Y663916D03*
X1176525Y679676D03*
X1170181Y670240D03*
X1176503Y670218D03*
X1182803Y670234D03*
X1176534Y673368D03*
X1179653Y670234D03*
X1173309Y673406D03*
X1179662Y673421D03*
X1176534Y676555D03*
X1179667Y679655D03*
X1182831Y679666D03*
X1182815Y676573D03*
X1170192Y667100D03*
X1176526Y667092D03*
X1173403Y670237D03*
X1173349Y667099D03*
X1182785Y685977D03*
X1176520Y685970D03*
X1179663Y685959D03*
X1173365Y695397D03*
X1169800Y682200D03*
X1173392Y685974D03*
X1173389Y689121D03*
X1176482Y682840D03*
X1176529Y692276D03*
X1179685Y692292D03*
X1176496Y695415D03*
X1179664Y695466D03*
X1182796Y695415D03*
X1179678Y689111D03*
X1182817Y689155D03*
X1173384Y692265D03*
X1182815Y701696D03*
X1182796Y708013D03*
X1182813Y698619D03*
X1170248Y714330D03*
X1173350Y698590D03*
X1179703Y714331D03*
X1173347Y714350D03*
X1176503Y714342D03*
X1176515Y704845D03*
X1179676Y711207D03*
X1179660Y704850D03*
X1171200Y706170D03*
X1179660Y708050D03*
X1176515Y708045D03*
X1173015Y708329D03*
X1176515Y711144D03*
X1173262Y711119D03*
X1182802Y714356D03*
X1169282Y729708D03*
X1173400Y717480D03*
X1176499Y720609D03*
X1170199Y717501D03*
X1173348Y720613D03*
X1176489Y717469D03*
X1171500Y733725D03*
X1175000Y734870D03*
X1171108Y777368D03*
X1170950Y795960D03*
X1170911Y784912D03*
X1170718Y782118D03*
X1185965Y676573D03*
X1190500Y674207D03*
X1190000Y699500D03*
Y705500D03*
X1199500Y743500D03*
X1201250Y627000D03*
X1218040Y719850D03*
X1249773Y551500D03*
X1279600Y694800D03*
X1287962Y710490D03*
X1289500Y716500D03*
X1292500Y730478D03*
X1305000Y596500D03*
X1306423Y608164D03*
X1306443Y618985D03*
X1307150Y691500D03*
X1307000Y729100D03*
X1310500Y737500D03*
X1307000Y732500D03*
X1300491Y732991D03*
X1322900Y524600D03*
X1322400Y533100D03*
X1318000Y696500D03*
X1319000Y708000D03*
X1351900Y524600D03*
X1352400Y533600D03*
X1381415Y581195D03*
X1380925Y598315D03*
X1377996Y610847D03*
X1380925Y602035D03*
X1377996Y607382D03*
X1385135Y581195D03*
G54D13*
X8200Y857700D03*
X8000Y853500D03*
X35304Y832220D03*
X34304Y897720D03*
X47483Y387776D03*
X43883Y387769D03*
X52000Y655500D03*
X44804Y837220D03*
X44500Y851500D03*
X49000Y861500D03*
X52000Y872720D03*
X37232Y877242D03*
X51896Y878668D03*
X42554Y891720D03*
X37211Y881115D03*
X37758Y884674D03*
X40304Y887220D03*
X51304Y882220D03*
X47804Y906720D03*
X43804Y907720D03*
X41304Y927220D03*
X50270Y929186D03*
X62783Y387776D03*
X66483Y387876D03*
X56883D03*
X53183Y387676D03*
X55304Y669720D03*
X58804Y710220D03*
X68147Y722511D03*
X62704Y739620D03*
X55304Y746220D03*
X65272Y758504D03*
X64683Y762056D03*
X59272Y790504D03*
X57772Y801504D03*
X61492Y803004D03*
X55022Y826720D03*
X66022Y827254D03*
X57304Y815720D03*
X61304Y815220D03*
X65804Y835720D03*
X57804Y834720D03*
X61804D03*
X52304Y868220D03*
X60804Y907720D03*
X56804Y907220D03*
X52304Y906720D03*
X64804Y907720D03*
X52804Y943220D03*
X57770Y932686D03*
X55270Y929186D03*
X52770Y932686D03*
X62770D03*
X60270Y929186D03*
X52804Y938795D03*
X71883Y387976D03*
X76083D03*
X76804Y710220D03*
X71846Y722426D03*
X77272Y724004D03*
X75432Y735059D03*
X83849Y735513D03*
X80272Y735103D03*
X68910Y760642D03*
X83112Y760720D03*
X75432Y758844D03*
X80624Y764241D03*
X68762Y764239D03*
X82804Y794920D03*
X84804Y808720D03*
X79000Y836500D03*
X84221Y836078D03*
X77500Y832000D03*
X70909Y847325D03*
X72304Y869720D03*
X76304D03*
X81304Y884470D03*
X89804Y669720D03*
X95304Y686220D03*
X94804Y708220D03*
X99804Y709220D03*
X87772Y735059D03*
X92365Y735040D03*
X85672Y763504D03*
X86404Y774720D03*
X85304Y768720D03*
X93347Y765754D03*
X85204Y798220D03*
X92304Y835720D03*
X87928Y848107D03*
X95700Y926300D03*
X105000Y834500D03*
X113222Y831222D03*
X112500Y835000D03*
X110500Y848500D03*
X115500D03*
X109054Y892720D03*
X102304Y895220D03*
X114054Y892720D03*
X106554Y895720D03*
X116554D03*
X111554Y896220D03*
X105804Y943220D03*
X109054Y932720D03*
X116600Y929924D03*
X114054Y932470D03*
X111554Y929720D03*
X108804Y938795D03*
X115500Y983500D03*
X127654Y293453D03*
X132123Y318877D03*
X123654Y320953D03*
X131500Y324000D03*
X122906Y331953D03*
X127301Y354709D03*
X131147D03*
X132500Y547000D03*
Y559600D03*
Y556000D03*
Y551500D03*
X133500Y582500D03*
X125050Y583000D03*
X126500Y587500D03*
X121685Y587919D03*
X134000Y587000D03*
X130000Y666500D03*
X129304Y798720D03*
X122500Y845500D03*
X128000Y870500D03*
X129100Y892924D03*
X124054Y892220D03*
X121600Y895266D03*
X119054Y892720D03*
X126554Y895470D03*
X121598Y929924D03*
X131554Y929470D03*
X129054Y932720D03*
X126554Y929882D03*
X124098Y932515D03*
X119099Y932516D03*
X118000Y991500D03*
X145500Y283500D03*
X143147Y354709D03*
X139301D03*
X147500Y472100D03*
X135500Y511000D03*
X136000Y566000D03*
X136500Y576900D03*
Y573300D03*
Y580500D03*
Y569700D03*
X140500Y568000D03*
X144000Y572500D03*
X143500Y710500D03*
X141054Y795820D03*
X150225Y790412D03*
X146304Y804220D03*
X146500Y808220D03*
X165793Y294309D03*
X155874Y313961D03*
Y317807D03*
X164147Y328699D03*
X155874Y326957D03*
Y323111D03*
X155147Y354709D03*
X162801D03*
X166647D03*
X151301D03*
X160000Y465500D03*
X153050Y486500D03*
X154625Y550290D03*
X163305Y554750D03*
X160500Y586500D03*
X156900D03*
X152948Y587000D03*
X166000Y662500D03*
X157750Y662250D03*
X166500Y650500D03*
X162500Y670000D03*
X163000Y710500D03*
X150900Y812500D03*
X154500D03*
X152500Y840000D03*
X157500Y867500D03*
X169639Y294309D03*
X179088Y294909D03*
X175242D03*
X167993Y328699D03*
X179622Y328749D03*
X175776D03*
X182800Y471300D03*
X171500Y478699D03*
X177493Y533493D03*
X175993Y559938D03*
X167469Y588969D03*
X174000Y830500D03*
X170500Y835500D03*
X179500Y847000D03*
X172000Y868000D03*
X168400D03*
X183000Y865750D03*
X188295Y297209D03*
X193841Y297755D03*
X185039Y295209D03*
X191295D03*
X186614Y319028D03*
X190295Y318709D03*
X198864Y323297D03*
X192874Y334307D03*
Y330461D03*
X184295Y322209D03*
X192795Y321709D03*
X192874Y341611D03*
Y345457D03*
X187300Y457300D03*
X191800D03*
X185000Y533562D03*
X185305Y521100D03*
X195865Y552940D03*
X198500Y563000D03*
X189500Y573500D03*
X194500Y724000D03*
X186000Y841500D03*
X185000Y856000D03*
X185500Y848260D03*
X187000Y878000D03*
X199000Y891500D03*
X190500Y894000D03*
X195000Y891500D03*
X204285Y294909D03*
X213733D03*
X200439D03*
X209887D03*
X208338Y323297D03*
X202710D03*
X212134D03*
X204500Y470000D03*
X207773Y516562D03*
X208305Y548670D03*
Y536320D03*
X203000Y564500D03*
X212500Y716500D03*
X204500Y721000D03*
X215250Y833750D03*
X205500Y830000D03*
X204000Y862000D03*
X212000Y891500D03*
X203500Y894000D03*
X208000Y892000D03*
X232500Y425000D03*
X229055Y497000D03*
X216500Y516000D03*
X228319Y524798D03*
X230000Y680500D03*
X221000Y723000D03*
X218000Y801500D03*
X223500Y825500D03*
X228000Y825000D03*
X232000D03*
X227000Y858000D03*
X217000Y858500D03*
X222000Y853500D03*
Y858500D03*
Y863500D03*
Y893600D03*
X243755Y490890D03*
X242003Y506327D03*
X234755Y509700D03*
X245205Y504679D03*
X246613Y501365D03*
X237055Y513500D03*
X234185Y527138D03*
X248855Y532300D03*
X239555Y519500D03*
X247500Y829500D03*
X237953Y861453D03*
X259055Y500500D03*
X260288Y514589D03*
X264655Y511100D03*
X250055Y510800D03*
X256055Y531016D03*
X260555Y525500D03*
X253679Y523137D03*
X260605Y519245D03*
X263555Y534500D03*
X261255Y549000D03*
X265455Y544853D03*
X252055Y548760D03*
X257555Y549000D03*
X251000Y835500D03*
X251500Y855500D03*
X252000Y846500D03*
X252500Y851500D03*
X250362Y865000D03*
X253610Y863447D03*
X279997Y514179D03*
X275555Y531500D03*
X275055Y521825D03*
X266055Y531725D03*
X272571Y541150D03*
X278367Y535140D03*
X269555Y536000D03*
X271451Y544616D03*
X278676Y539500D03*
X270000Y870000D03*
Y865500D03*
X276500Y888500D03*
X280500Y955000D03*
X278050Y958500D03*
X296200Y94400D03*
X292525Y498780D03*
X292045Y504897D03*
X293273Y509500D03*
X282626Y516639D03*
X291530Y525407D03*
X283103Y520208D03*
X286588Y519305D03*
X292555Y533043D03*
X291755Y529000D03*
X286555Y524524D03*
X282555Y540700D03*
X283038Y536850D03*
X309500Y78500D03*
X313250Y85250D03*
X311500Y81500D03*
X314000Y102500D03*
X302000Y94300D03*
X299831Y144328D03*
X303677D03*
X305852Y163800D03*
X309698D03*
X299395Y449160D03*
X312925Y462560D03*
X298662Y479783D03*
X305055Y472500D03*
X302555Y476000D03*
X312773Y529878D03*
X313000Y582000D03*
X327000Y89500D03*
X323000D03*
X319309Y89503D03*
X317500Y101000D03*
X324200Y101900D03*
X330000Y118500D03*
X325929D03*
X321500D03*
X327100Y136294D03*
Y139857D03*
X326422Y152507D03*
Y148944D03*
X319800Y146898D03*
Y143052D03*
X322229Y218800D03*
X316129Y213000D03*
X328000Y285000D03*
X330555Y467500D03*
X325873Y477006D03*
X325854Y480606D03*
X317195Y493280D03*
X317255Y514170D03*
X330491Y525490D03*
X315725Y549790D03*
X329695Y534650D03*
X317758Y581297D03*
X329055Y569500D03*
X321780Y575000D03*
X314930Y585500D03*
X321500Y688000D03*
X333000Y90500D03*
X343000Y89000D03*
X339500Y75500D03*
X337500Y84250D03*
X342000Y102000D03*
X346000D03*
X334500Y118500D03*
X334600Y129468D03*
Y133031D03*
X343929Y320700D03*
X344929Y325500D03*
X342500Y340000D03*
X338500Y397500D03*
X336375Y452870D03*
X338985Y467405D03*
X343688Y509533D03*
X334055Y526000D03*
X347213Y546700D03*
X334555Y548500D03*
X341055Y534500D03*
X344655D03*
X345500Y556500D03*
X339888Y586388D03*
X346402Y653004D03*
X342500Y653000D03*
X335500Y868000D03*
X332129Y889371D03*
X331829Y885500D03*
X338000Y942000D03*
X339500Y960000D03*
X352000Y66000D03*
X357500Y79500D03*
Y75500D03*
X351929Y332500D03*
X364015Y468450D03*
X349575Y479503D03*
X349815Y475550D03*
X358797Y532258D03*
X354055Y534000D03*
X352095Y524040D03*
X362555Y534500D03*
X348255D03*
X360500Y588500D03*
X350000Y652878D03*
X362210Y876200D03*
X363480Y907783D03*
X362000Y904500D03*
X363000Y931500D03*
X359000D03*
X354000Y960000D03*
X363614Y971524D03*
X361000Y974000D03*
X360024Y979100D03*
X366600Y285800D03*
X377855Y300110D03*
X374000Y293500D03*
X372055Y364000D03*
X370275Y413540D03*
X371710Y406535D03*
X369555Y417500D03*
X370575Y409952D03*
X375055Y444500D03*
X367022Y482783D03*
X378255Y471840D03*
X379000Y531000D03*
X371000Y866500D03*
X376041Y866041D03*
X375500Y906000D03*
Y901500D03*
X365500Y916000D03*
X369341Y916117D03*
X371100Y926000D03*
X377000Y927500D03*
X372300Y918749D03*
X369500Y936500D03*
X368000Y932000D03*
X371000Y930000D03*
X376000Y960000D03*
X364396Y980109D03*
X366878Y977500D03*
X369200Y980252D03*
X372500Y977918D03*
X377464Y987493D03*
X377250Y982250D03*
X390000Y13500D03*
X385000D03*
X388000Y233500D03*
X388149Y229780D03*
X393429Y229500D03*
X395450Y265400D03*
X390100Y263600D03*
X387500Y261000D03*
X381500Y297000D03*
X395104Y291056D03*
X382455Y331870D03*
X393055Y451000D03*
Y447400D03*
X385463Y450948D03*
X386055Y454500D03*
X388885Y471100D03*
X381500Y534000D03*
X384046Y536546D03*
X396000Y714500D03*
X392500Y718500D03*
X391000Y866500D03*
X396500Y888500D03*
X396600Y895855D03*
X396330Y899705D03*
X396500Y904000D03*
X384000Y926500D03*
X389838Y942300D03*
X388500Y955250D03*
X390000Y946500D03*
X397900Y231800D03*
X399500Y240500D03*
X401855Y293500D03*
X408656Y291500D03*
X405555Y293500D03*
X406555Y320500D03*
X403255Y425950D03*
X404500Y877300D03*
X397600Y892000D03*
X399500Y901500D03*
X403250Y949000D03*
X408250Y949500D03*
X410500Y954500D03*
X405704Y952046D03*
X398250Y955000D03*
X400750Y952000D03*
X410000Y983500D03*
X410500Y987500D03*
X414000Y8000D03*
X418192Y114237D03*
X421000Y231500D03*
X424929Y264700D03*
X428100Y266500D03*
X419600Y282900D03*
X419455Y293000D03*
X416187Y294711D03*
X429500Y311000D03*
X425278Y802000D03*
X416046Y959546D03*
X414500Y948500D03*
X414215Y952089D03*
X422098Y948630D03*
X418500Y948500D03*
X413500Y957000D03*
X416000Y964000D03*
X420000D03*
X413600Y983500D03*
X438500Y9000D03*
X433929Y100000D03*
Y264300D03*
X439800Y284100D03*
X439200Y294550D03*
X432500Y301000D03*
X435000Y294000D03*
X444778Y802100D03*
X438278D03*
X431778Y802000D03*
X431278Y883000D03*
X444278D03*
X437778D03*
X432000Y933500D03*
X430500Y962000D03*
X459429Y106000D03*
X448929Y99500D03*
X450929Y118000D03*
X462500Y169000D03*
X455054Y179475D03*
X458429Y175590D03*
X456000Y243500D03*
X460000D03*
X461100Y260050D03*
X459055Y263500D03*
X456278Y802100D03*
X450778Y883000D03*
X460778D03*
X471290Y118361D03*
X469000Y113000D03*
X472990Y113350D03*
X462700Y120800D03*
X477291Y147500D03*
X477900Y153600D03*
X471000Y141000D03*
X477929Y158000D03*
X467600Y158400D03*
X465600Y162000D03*
X475216Y182917D03*
X470000Y188500D03*
X462679Y176900D03*
X466700Y259400D03*
X464055Y256500D03*
X463371Y290371D03*
X464200Y307838D03*
X463945Y349700D03*
X475778Y802100D03*
X462778D03*
X469278D03*
X473778Y883000D03*
X467278D03*
X488500Y114200D03*
X481429Y150000D03*
X491257Y315952D03*
X495103D03*
X487612Y318606D03*
X480278Y883000D03*
X488000Y904500D03*
X483500Y907500D03*
X499390Y153500D03*
X503500D03*
X503929Y146500D03*
X506429Y149500D03*
X495929Y164500D03*
X508500Y320000D03*
X504453Y314200D03*
X500607D03*
X496155Y321700D03*
X505922Y415371D03*
X506163Y419973D03*
X508100Y605500D03*
X506000Y610000D03*
X513200Y121450D03*
X513000Y156500D03*
X512000Y320000D03*
X519706Y314000D03*
X515860D03*
X527002Y319359D03*
X523348D03*
X526500Y346532D03*
Y342969D03*
Y352969D03*
X520500Y351500D03*
Y347937D03*
Y358937D03*
X526500Y356532D03*
X520500Y362500D03*
X533000Y153800D03*
X528500Y172000D03*
X539714Y179150D03*
X542500Y188500D03*
X537479Y197875D03*
X539073Y237300D03*
X531590Y297620D03*
X534500Y295500D03*
X528500Y310000D03*
X534629Y311171D03*
X534960Y321000D03*
X538614D03*
X529848Y325500D03*
X533502D03*
X550500Y188000D03*
X560500Y186000D03*
X555500Y194000D03*
X559500D03*
X545000Y195000D03*
X549926Y204000D03*
X557275Y214918D03*
X553675Y215913D03*
X550075D03*
X559961Y209419D03*
X546916Y217641D03*
X548000Y231000D03*
X547746Y225303D03*
X559971Y237753D03*
X553555Y321000D03*
X560253Y329500D03*
X557061Y334194D03*
X553155Y334300D03*
X548000Y369500D03*
X555935Y363000D03*
X559500Y604500D03*
X572000Y189000D03*
X571398Y183602D03*
X561429Y174441D03*
X575500Y198400D03*
X576650Y204500D03*
X563100Y194000D03*
X568158Y206455D03*
X571461Y207887D03*
X569000Y217000D03*
X569127Y213100D03*
X564583Y206028D03*
X577119Y233139D03*
X564631Y234356D03*
X569322Y234220D03*
X573179Y233535D03*
X575425Y228505D03*
X563704Y272000D03*
X563555Y333000D03*
X564215Y369339D03*
X566430Y366500D03*
X569555Y364000D03*
X562555Y364500D03*
X587175Y202525D03*
X591413Y199087D03*
X583500Y204500D03*
X585325Y198000D03*
X583325Y208500D03*
X583204Y236805D03*
X580709Y232091D03*
X619876Y195000D03*
X617828Y303250D03*
X613962D03*
X623500Y576500D03*
X622500Y608500D03*
X633578Y303250D03*
X629712D03*
X642800Y433587D03*
X641500Y449500D03*
X636500Y444800D03*
X640500Y444500D03*
X635325Y457500D03*
X628524Y591976D03*
X649323Y303250D03*
X645457D03*
X652714Y428214D03*
X647500Y425500D03*
X645500Y459500D03*
X654300Y490300D03*
X674469Y99380D03*
X674358Y103170D03*
X665073Y303250D03*
X661207D03*
X669025Y441725D03*
X660500Y436538D03*
X669462Y472500D03*
X667056Y475500D03*
X673010Y474436D03*
X673300Y579000D03*
X669000D03*
X663500Y610500D03*
X674688Y696751D03*
X670474Y808700D03*
X671500Y861000D03*
X673500Y864000D03*
X672000Y967750D03*
X667000Y969700D03*
X666750Y961550D03*
X685519Y55019D03*
X676748Y52000D03*
X684861Y58584D03*
X686000Y62000D03*
X684197Y74703D03*
X687500Y440500D03*
X677500Y472500D03*
X688500Y606000D03*
X683000Y603950D03*
X677500Y612000D03*
X680000Y640000D03*
X691000Y704500D03*
X677500Y699000D03*
X682968Y758284D03*
X677500Y773500D03*
X678468Y805284D03*
X691300Y807300D03*
X679000Y865050D03*
X676500Y967750D03*
X706716Y82448D03*
X705500Y575600D03*
X702918Y782734D03*
X704000Y892500D03*
X716034Y53966D03*
X716466Y65466D03*
X711216Y82402D03*
X720216Y82138D03*
X711500Y179400D03*
X725000Y452300D03*
X720700Y564200D03*
X717036Y563783D03*
X709750Y585200D03*
X719918Y754734D03*
X715118Y776134D03*
X717468Y810784D03*
X722000Y808500D03*
X720500Y860000D03*
X710750Y863250D03*
X714000Y867500D03*
X714500Y891000D03*
X740500Y75000D03*
X728100Y213800D03*
X732500Y455500D03*
X736000Y464500D03*
X728500Y482500D03*
X730000Y536500D03*
X733500Y568500D03*
X729900D03*
X741500Y582450D03*
X737000Y583640D03*
X740768Y763984D03*
X735500Y771984D03*
X736000Y810500D03*
X733768Y800734D03*
X741050Y869500D03*
X740000Y886000D03*
X737290Y903000D03*
X733000Y969700D03*
X754500Y67500D03*
X747000Y210000D03*
X755697Y303250D03*
X751484Y540600D03*
X755000Y727500D03*
X757500Y743500D03*
X757000Y896400D03*
X749500Y974300D03*
X759563Y303250D03*
X771447D03*
X773500Y326000D03*
X758500Y457000D03*
X772024Y478976D03*
X774500Y489500D03*
X760500D03*
X766000Y635000D03*
X763000Y648000D03*
X767000Y648500D03*
X771000Y689500D03*
X760500Y707950D03*
X768000Y728000D03*
X763500Y839500D03*
X768000Y833000D03*
X766750Y849250D03*
X774500Y890500D03*
X775748Y188500D03*
X789500Y235837D03*
X787192Y303250D03*
X775313D03*
X779000Y458000D03*
X776000Y478828D03*
X788774Y482774D03*
X786500Y575688D03*
X786032Y570468D03*
X783500Y649000D03*
X784804Y673304D03*
X779500Y705000D03*
X785000Y892000D03*
X785500Y969700D03*
X796000Y167600D03*
X795500Y163408D03*
X802942Y303250D03*
X791058D03*
X806808D03*
X798000Y400500D03*
X796074Y479000D03*
X803500Y655000D03*
X798000Y706000D03*
X802000Y724000D03*
X801750Y867500D03*
X818000Y240900D03*
X821100Y348480D03*
Y352480D03*
X808500Y363500D03*
X823500Y480000D03*
X814500Y472500D03*
X823500Y556500D03*
X815900Y564000D03*
X819500D03*
X821250Y845750D03*
X810500Y851000D03*
X819000Y868500D03*
X832000Y137500D03*
X826198Y239950D03*
X833555Y262000D03*
X833500Y613000D03*
X835000Y719000D03*
X826500Y743000D03*
X824560Y868560D03*
X856055Y262500D03*
X842555Y262000D03*
X850540Y346070D03*
X844410Y346360D03*
X847500Y352000D03*
X849500Y622000D03*
X846500Y710000D03*
X845500Y865000D03*
X873000Y68500D03*
X870100Y237500D03*
X869544Y226000D03*
X860400Y231000D03*
X860555Y262500D03*
X863820Y363880D03*
X868820D03*
X870500Y444000D03*
Y448000D03*
X857500Y485500D03*
X862500Y621250D03*
X859500Y629500D03*
X872000Y636000D03*
X867500Y655200D03*
X860718Y683684D03*
X877860Y316330D03*
X887950Y359730D03*
X874910Y360160D03*
X879510Y355410D03*
X887940Y380200D03*
X878000Y404500D03*
X876000Y435500D03*
X886300Y443100D03*
X882700D03*
X885000Y438700D03*
X877000Y479500D03*
X876000Y631700D03*
X881000Y710000D03*
X899000Y312500D03*
X898000Y316000D03*
X903480Y324230D03*
X893500Y427000D03*
X893600Y443100D03*
X889900D03*
X903075Y472000D03*
X918420Y449130D03*
X907000Y465050D03*
X917000Y752500D03*
X923000Y51500D03*
X924465Y388465D03*
X936030Y457540D03*
X937000Y489000D03*
X935400Y597300D03*
X939500Y352000D03*
X953500Y348927D03*
X944000Y434000D03*
X958500Y187500D03*
X957990Y191064D03*
X962000Y251500D03*
X965500Y260500D03*
X963500Y256000D03*
X959500Y351688D03*
X965000Y364500D03*
X964000Y354000D03*
X970382Y455872D03*
X961700Y477500D03*
X957500Y585500D03*
X961500D03*
X970750Y703000D03*
X980490Y198827D03*
X982075Y439500D03*
X973015Y453416D03*
X977000Y547500D03*
X982500Y549500D03*
X978000Y554000D03*
X975000Y701000D03*
X1003000Y59500D03*
X988900Y434800D03*
X992690Y466750D03*
X996910Y466560D03*
X994500Y491000D03*
X1003422Y490578D03*
X992000Y505500D03*
X990500Y536500D03*
X998500Y591500D03*
X989000Y659500D03*
Y757150D03*
X1016500Y87500D03*
X1020500Y124500D03*
Y142000D03*
X1014000Y487000D03*
X1007500Y507000D03*
X1008500Y533400D03*
X1013500Y559000D03*
X1016900Y561000D03*
X1017982Y585018D03*
X1007532Y902468D03*
X1033500Y118000D03*
X1025500Y129500D03*
X1033500Y124000D03*
X1037085Y137000D03*
X1023000Y155000D03*
X1028000Y164500D03*
X1023600Y173000D03*
X1031524Y218476D03*
X1033900Y225500D03*
X1027426Y346500D03*
X1023000Y347000D03*
X1031000Y348500D03*
Y355950D03*
X1030000Y403500D03*
X1036500Y581500D03*
X1035000Y594500D03*
X1021000Y588500D03*
X1025500Y657000D03*
X1023500Y727000D03*
X1037000Y734000D03*
X1024387Y738230D03*
X1035000Y800000D03*
Y804500D03*
X1032657Y901500D03*
X1027716Y914784D03*
X1032200Y921500D03*
X1045031Y138031D03*
X1041485Y137409D03*
X1040000Y182000D03*
X1052500Y187500D03*
X1037500Y225500D03*
X1040000Y579000D03*
X1038000Y604000D03*
X1053500Y620500D03*
X1046000Y644000D03*
X1038000Y635000D03*
X1042450Y648500D03*
X1045500Y639500D03*
X1050092Y655052D03*
X1042400Y684500D03*
X1052500Y693000D03*
X1052678Y704084D03*
X1038500Y706500D03*
X1052500Y709000D03*
Y700000D03*
X1041410Y708804D03*
Y704224D03*
X1052648Y712724D03*
X1040208Y745020D03*
X1052500Y773350D03*
X1044000Y763940D03*
X1064000Y80000D03*
X1055500D03*
X1059500D03*
X1068000D03*
Y76000D03*
X1064000D03*
X1059500D03*
X1055500D03*
X1068500Y118500D03*
X1069000Y124500D03*
X1060900Y173534D03*
X1056500Y194000D03*
X1061000Y211500D03*
X1055000Y219284D03*
X1060766Y395426D03*
X1061200Y399000D03*
X1068300Y488700D03*
X1059000Y558190D03*
X1058000Y599500D03*
X1056000Y604000D03*
X1058500Y660900D03*
X1054900D03*
X1070000Y650725D03*
X1058350Y681450D03*
X1068500Y677000D03*
X1054500Y697000D03*
X1068500Y687000D03*
X1066000Y717000D03*
X1059800Y719740D03*
X1054000Y735000D03*
X1056350Y748000D03*
X1063000Y780000D03*
X1072000Y136000D03*
X1080300Y191000D03*
X1084500Y202500D03*
X1078500Y464000D03*
X1080000Y520000D03*
X1081000Y548000D03*
Y544400D03*
X1084599Y544520D03*
X1086000Y556000D03*
X1071500Y589000D03*
X1085000Y661000D03*
X1074000Y677000D03*
X1073500Y672000D03*
X1074000Y683000D03*
X1074500Y694754D03*
X1074426Y687255D03*
X1074389Y691155D03*
X1074000Y699500D03*
X1074148Y711624D03*
X1074600Y707724D03*
X1074000Y703500D03*
X1073384Y722384D03*
X1073000Y730834D03*
Y726444D03*
X1074288Y715534D03*
X1084300Y741874D03*
X1077500Y745374D03*
X1072000Y743500D03*
X1084000Y748099D03*
X1070098Y764500D03*
X1083700Y835725D03*
X1077000Y943075D03*
X1083200Y956500D03*
X1093894Y126500D03*
X1090028D03*
X1092500Y461500D03*
X1098500Y465000D03*
X1089000Y508500D03*
X1100575Y559075D03*
X1098000Y562000D03*
X1091425Y551425D03*
X1093500Y640000D03*
X1094500Y657500D03*
X1091000Y692519D03*
X1090257Y724253D03*
X1087600Y727029D03*
X1094853Y726853D03*
X1095500Y812000D03*
X1097500Y849000D03*
X1089000Y867284D03*
X1099623Y869123D03*
X1097423Y906546D03*
X1093500Y905500D03*
X1110318Y275600D03*
X1111500Y517500D03*
X1107500Y580000D03*
X1114883Y591925D03*
X1106000Y609500D03*
Y605500D03*
X1111500Y718500D03*
X1107000Y763000D03*
X1110300Y790000D03*
X1111834Y813334D03*
X1113500Y824500D03*
X1111000Y836000D03*
X1107160Y843160D03*
X1128000Y288500D03*
X1132300Y288800D03*
X1130000Y361500D03*
X1124327Y465391D03*
X1123500Y521500D03*
X1128149Y525261D03*
X1130928Y527550D03*
X1132000Y562000D03*
X1125600Y570600D03*
X1135000Y597000D03*
X1132222Y593278D03*
X1119487Y588088D03*
X1122353Y590268D03*
X1125000Y603050D03*
X1134000Y613500D03*
X1126000Y627329D03*
X1131000Y631000D03*
X1121500Y621600D03*
X1130490Y627436D03*
X1125041Y631000D03*
X1120500Y729500D03*
X1124000Y729000D03*
X1128430Y749640D03*
X1126642Y785505D03*
X1123200Y783900D03*
X1130030Y820000D03*
X1146500Y267000D03*
X1146000Y258500D03*
X1151000Y264500D03*
X1146500Y275500D03*
X1136100Y288900D03*
X1136450Y294650D03*
X1150640Y359860D03*
X1146640D03*
X1142640D03*
X1151500Y522000D03*
X1143500Y542000D03*
X1147500D03*
X1136075Y559075D03*
X1145900Y579800D03*
X1136500Y592500D03*
X1139632Y594441D03*
X1140500Y589000D03*
X1141100Y585400D03*
X1147400Y729900D03*
X1153700Y267700D03*
X1156100Y316405D03*
Y312795D03*
X1165000Y308175D03*
Y304565D03*
X1161530Y360430D03*
X1157480Y361620D03*
X1157700Y368500D03*
X1160058Y364558D03*
X1155400Y371500D03*
X1164000Y397000D03*
X1168000Y390250D03*
X1166500Y415500D03*
X1155500Y450758D03*
Y446892D03*
X1161000Y541500D03*
X1154000Y589000D03*
X1164500Y628723D03*
X1159075Y630600D03*
X1154847Y630908D03*
X1156377Y627623D03*
X1153500Y784190D03*
X1164500Y857500D03*
X1162000Y960625D03*
X1181427Y251500D03*
X1180677Y256500D03*
X1173777Y290125D03*
X1169777D03*
X1173125Y323716D03*
X1169515D03*
X1184000Y351500D03*
X1174500Y366000D03*
X1182000Y357000D03*
X1174400Y356500D03*
X1178000D03*
X1175125Y370000D03*
X1174500Y404000D03*
X1173500Y422500D03*
Y554000D03*
X1181350Y595450D03*
X1169075Y613500D03*
X1183000Y628000D03*
X1177100Y624750D03*
X1178500Y653100D03*
X1184500Y749500D03*
Y772782D03*
X1173200Y789500D03*
X1177000Y860000D03*
X1169000Y856000D03*
X1181500Y949000D03*
X1188000Y248500D03*
X1192743Y289800D03*
X1188877D03*
X1199685Y344588D03*
X1196075D03*
X1189000Y421500D03*
X1195000Y428000D03*
X1197675Y533125D03*
X1191000Y528000D03*
X1189000Y533825D03*
X1194564Y530936D03*
X1185500Y548075D03*
X1200500Y547925D03*
X1186000Y615500D03*
X1196000Y605800D03*
X1184956Y619272D03*
X1191000Y663000D03*
X1193804Y657175D03*
X1191000Y667000D03*
X1197500Y665500D03*
X1199551Y683968D03*
X1195937Y683849D03*
X1189890Y684053D03*
X1192937Y683911D03*
X1196500Y745500D03*
Y736687D03*
X1192500Y745500D03*
X1192038Y761481D03*
X1188500Y773000D03*
X1184975Y767500D03*
X1194000Y764500D03*
X1190000Y767500D03*
X1196000Y847500D03*
Y874500D03*
X1207500Y239500D03*
X1210800Y379700D03*
X1216000Y390000D03*
X1209500Y404500D03*
X1216500Y439500D03*
X1212500Y436000D03*
X1217000Y452500D03*
X1210000Y507500D03*
X1209500Y514000D03*
X1213100D03*
X1214450Y509000D03*
X1206400Y536800D03*
X1210000D03*
X1201500Y535000D03*
X1205240Y568760D03*
X1207700Y605500D03*
X1208500Y623000D03*
X1204500Y659500D03*
X1203181Y683968D03*
X1206781Y684003D03*
X1213598Y699164D03*
X1216000Y702500D03*
X1206500Y757000D03*
X1213500Y756000D03*
X1202218Y811282D03*
X1211000Y847500D03*
X1208940Y874560D03*
X1227500Y500500D03*
Y504246D03*
X1220500Y513000D03*
X1229500Y533000D03*
X1231632Y537000D03*
X1221500Y539500D03*
X1233000Y554502D03*
X1219200Y564600D03*
X1221500Y633000D03*
X1231450Y677500D03*
X1229000Y716000D03*
Y726500D03*
Y719600D03*
Y740000D03*
X1230219Y747469D03*
X1232000Y738000D03*
X1234000Y747500D03*
X1224500Y757500D03*
X1228547Y772547D03*
Y778453D03*
X1231000Y768500D03*
X1221000Y764750D03*
X1233000Y782500D03*
X1223500Y798500D03*
X1223000Y826500D03*
X1218500Y834500D03*
X1229807Y847000D03*
X1239000Y190500D03*
X1240000Y209449D03*
X1243000Y431500D03*
X1250000Y422000D03*
X1234500Y439000D03*
X1248250Y439250D03*
X1250450Y462000D03*
X1242000Y459000D03*
X1247800Y472750D03*
X1246750Y476250D03*
X1249000Y509500D03*
X1249251Y528688D03*
X1235482Y546982D03*
X1240000Y546500D03*
Y542900D03*
X1240173Y550327D03*
X1250500Y567000D03*
X1241000Y631500D03*
X1237500Y675500D03*
X1239500Y671000D03*
X1235000Y682000D03*
X1244371Y733129D03*
X1236500Y737925D03*
X1243000Y743000D03*
X1241000Y734500D03*
X1240016Y761500D03*
X1238000Y764500D03*
X1249500Y765500D03*
X1248950Y769500D03*
X1238047Y791953D03*
X1240045Y788957D03*
X1241984Y796000D03*
X1243953Y789000D03*
X1240660Y829000D03*
X1235258Y820758D03*
X1257000Y33000D03*
X1260677Y237000D03*
X1264177Y233500D03*
X1256000Y252000D03*
X1262558Y254942D03*
X1261677Y241500D03*
Y245500D03*
X1264500Y260000D03*
X1254944Y268567D03*
X1263000Y278500D03*
X1250677Y287500D03*
Y283500D03*
X1254944Y272433D03*
X1260577Y299968D03*
Y296102D03*
X1253477Y312800D03*
X1253577Y308800D03*
X1253177Y320500D03*
Y324500D03*
X1265000Y426500D03*
X1253000Y511000D03*
X1251500Y531500D03*
X1260500Y546400D03*
X1263500Y550000D03*
X1258000Y555400D03*
X1255000Y609300D03*
X1266500Y617500D03*
X1265000Y647500D03*
X1257500Y635500D03*
X1265000Y661000D03*
Y657000D03*
X1265500Y652500D03*
X1257100Y664300D03*
X1263121Y678621D03*
X1259000Y678950D03*
X1262300Y670700D03*
X1266000Y665600D03*
X1262500Y699825D03*
X1253500Y778465D03*
X1257950Y809250D03*
X1279500Y150500D03*
X1276500Y234000D03*
X1267677Y232500D03*
X1280500Y338000D03*
Y404550D03*
X1280000Y420500D03*
X1272500Y466600D03*
X1274500Y606000D03*
X1278500Y603500D03*
X1271000Y617500D03*
X1279340Y618660D03*
X1272451Y642500D03*
X1272502Y638900D03*
X1281268Y661780D03*
X1268805Y655405D03*
X1282500Y669561D03*
X1273702Y667662D03*
X1275885Y670525D03*
X1267500Y675000D03*
Y684878D03*
X1281500Y713000D03*
X1279000Y746575D03*
X1267500Y783000D03*
X1269500Y835000D03*
X1299500Y236000D03*
X1292500Y402000D03*
X1289000Y415500D03*
X1285700Y529700D03*
X1293960Y528740D03*
X1294600Y524200D03*
X1291300Y540900D03*
X1294000Y587500D03*
X1288335Y594048D03*
X1287482Y590500D03*
X1293500Y593000D03*
X1285557Y585000D03*
X1289570Y597430D03*
X1284825Y621500D03*
X1294000Y628000D03*
X1299000Y641500D03*
X1296000Y638500D03*
X1290500Y635500D03*
X1286500Y652500D03*
X1297500Y665000D03*
X1289500Y669000D03*
X1284490Y710936D03*
X1296500Y830782D03*
X1306000Y43000D03*
X1304050Y296500D03*
X1307500Y320500D03*
X1308000Y311000D03*
X1312750Y314000D03*
X1306000Y329000D03*
Y334500D03*
Y338500D03*
X1311000Y463500D03*
X1302000Y475000D03*
X1304700Y536000D03*
X1302500Y559500D03*
X1307000Y573412D03*
X1306817Y592412D03*
X1310500Y625000D03*
X1312000Y645784D03*
X1310425Y660062D03*
X1311100Y656400D03*
X1304400Y661400D03*
X1311700Y681500D03*
X1312115Y672000D03*
X1311000Y677284D03*
X1311300Y687500D03*
X1313500Y710000D03*
X1305000Y739750D03*
X1308100Y748200D03*
X1312500Y838000D03*
X1305000Y850500D03*
X1312000D03*
X1314500Y921500D03*
X1322500Y299000D03*
X1324000Y290500D03*
X1322500Y337000D03*
X1317000Y336000D03*
X1330500Y441000D03*
X1332000Y459250D03*
X1323500Y452500D03*
X1326617Y594412D03*
X1325950Y599000D03*
X1329317Y626512D03*
X1328000Y649000D03*
X1328968Y679684D03*
X1323500Y702000D03*
X1322000Y705500D03*
X1325250Y834250D03*
X1316500Y839000D03*
X1317000Y850500D03*
X1318113Y846371D03*
X1339000Y54000D03*
X1347000Y48000D03*
X1342500Y51000D03*
X1333100Y58600D03*
X1343500Y112000D03*
X1336500Y270874D03*
X1339000Y274000D03*
X1339500Y305500D03*
X1341873Y344873D03*
X1335000Y443250D03*
X1335317Y575412D03*
X1342648Y612412D03*
X1347617Y610412D03*
X1334500Y636000D03*
Y669000D03*
X1352000Y85500D03*
X1349500Y112000D03*
X1350000Y276500D03*
X1350084Y296500D03*
X1353000Y390000D03*
Y402000D03*
X1362500Y459000D03*
X1353500Y466500D03*
X1351000Y455750D03*
X1356817Y579012D03*
X1364617Y592912D03*
X1360200Y614800D03*
X1353517Y627512D03*
X1357300Y617700D03*
X1379500Y274500D03*
X1381500Y292000D03*
X1376000D03*
X1379500Y314000D03*
X1370500Y356500D03*
X1374500Y462800D03*
X1367617Y570012D03*
X1390004Y122600D03*
X1384500Y274500D03*
Y331500D03*
G54D47*
X1379862Y108465D03*
Y119095D03*
G54D43*
X1258504Y329331D03*
Y368701D03*
G54D42*
X1224016Y386221D03*
G54D12*
X21220Y373228D03*
X96890D03*
X157480Y283071D03*
X220472D03*
G54D18*
X121890Y269528D03*
X131890D03*
X141890D03*
X1346396Y21656D03*
X1338526D03*
X1346396Y29526D03*
X1362146Y21656D03*
X1354271D03*
X1362146Y29526D03*
X1354271D03*
X1377896Y21656D03*
X1370021D03*
X1377896Y29526D03*
X1370021D03*
X1385766Y21656D03*
Y29526D03*
G54D19*
X121000Y545500D03*
X146364Y296000D03*
X156500Y939500D03*
X162000D03*
X168000Y575000D03*
Y580000D03*
X178000Y590000D03*
X167500Y939500D03*
X172500D03*
X177500D03*
X182000D03*
X188000D03*
X193500D03*
X199500D03*
X207100Y703600D03*
X222000Y703500D03*
X224000Y875000D03*
X225500Y879500D03*
X225000Y920500D03*
X232000Y921000D03*
X227500Y957500D03*
Y963500D03*
X247500Y883000D03*
X243000D03*
X246968Y957784D03*
X233468Y957284D03*
X239968Y957784D03*
X246968Y963784D03*
X239968D03*
X233468D03*
X259000Y211000D03*
Y206000D03*
X262500Y208500D03*
X252000Y883000D03*
X256500D03*
X261000D03*
X265500D03*
X252000Y957500D03*
X252500Y963500D03*
X281800Y183700D03*
Y188500D03*
X281900Y178500D03*
X278500Y965000D03*
X277500Y969500D03*
X272500D03*
X268000D03*
X296000Y105000D03*
X285800Y180800D03*
X285600Y186100D03*
X285500Y330000D03*
X286000Y336000D03*
X306000Y105000D03*
X301000D03*
X310929Y257500D03*
X311429Y334500D03*
X307429Y336000D03*
Y331500D03*
X320500Y11000D03*
X316000D03*
X324000Y24000D03*
Y19500D03*
Y15000D03*
X330500Y38500D03*
Y33500D03*
X315929Y253000D03*
Y257500D03*
X344000Y27000D03*
X336000D03*
X337500Y102000D03*
X349000Y38500D03*
Y33500D03*
X351929Y266000D03*
X357661Y434216D03*
X364055Y428500D03*
X361055Y431500D03*
X362500Y608500D03*
X355500D03*
Y614000D03*
X362500D03*
X370500Y72100D03*
X376500Y608500D03*
X369500D03*
Y614000D03*
X376500D03*
X393800Y25100D03*
X389300Y20100D03*
X393800D03*
X384800Y25100D03*
X389300D03*
X384800Y20100D03*
X391000Y35500D03*
X395500D03*
X393900Y30400D03*
X389400D03*
X384900D03*
X386000Y53000D03*
X381500D03*
Y58000D03*
X398300Y20100D03*
Y25100D03*
X400000Y35500D03*
X398400Y30400D03*
X398000Y39500D03*
X403155Y437600D03*
X445395Y317610D03*
X432678Y827300D03*
X430778Y864000D03*
X453878Y824900D03*
X456278Y866500D03*
X467000Y118500D03*
X482429Y139000D03*
X482778Y832000D03*
X482278Y867500D03*
X495000Y883000D03*
X501000Y876000D03*
X499000Y883000D03*
X516000Y134000D03*
X519929Y135500D03*
X521055Y528500D03*
Y533500D03*
X516555Y528500D03*
Y533500D03*
X526055D03*
X526000Y524500D03*
Y529000D03*
X521000Y524000D03*
X521055Y544000D03*
Y548900D03*
X516555Y543500D03*
X516655Y548900D03*
X521055Y538500D03*
X516555Y539000D03*
X526055Y538500D03*
Y544000D03*
Y548900D03*
X516500Y556000D03*
X591000Y253500D03*
Y262500D03*
X586000Y267000D03*
Y262500D03*
X591000Y258000D03*
X586150Y383000D03*
X586200Y378500D03*
X581950Y383000D03*
X582000Y378500D03*
X590500Y383000D03*
X586150Y396000D03*
X590500D03*
X581950D03*
X586150Y409500D03*
X581950D03*
X590500D03*
X582700Y431500D03*
X590500Y423500D03*
X586150D03*
X587000Y431500D03*
X578500D03*
X581950Y423500D03*
X582200Y439500D03*
X578000D03*
X586500D03*
X593500Y648500D03*
Y659500D03*
Y654000D03*
X595500Y253500D03*
Y258000D03*
X610000Y415500D03*
Y434000D03*
Y428500D03*
Y422000D03*
X610100Y439500D03*
X602500Y465900D03*
X608000Y465800D03*
X602500Y470100D03*
X608000Y470300D03*
X601000Y543000D03*
X599500Y648500D03*
Y654000D03*
Y659500D03*
X609500Y778500D03*
X603000D03*
Y785000D03*
X609000Y870000D03*
X604000Y877500D03*
X609211Y877611D03*
X614200Y415500D03*
X614500Y434000D03*
X614200Y422000D03*
Y428500D03*
X614300Y439500D03*
X620000Y465800D03*
X613500D03*
X626500D03*
X613500Y470000D03*
X620000D03*
X626500D03*
Y557350D03*
X637500Y367900D03*
X630500Y368500D03*
X642000D03*
X647500D03*
X653500D03*
X659500D03*
X645500Y481000D03*
X674666Y82002D03*
X670998Y116010D03*
X665000Y368500D03*
X670000Y395000D03*
X670500Y414000D03*
X685898Y133380D03*
X682418Y129980D03*
X685000Y150500D03*
X701949Y118331D03*
X701828Y129550D03*
X698500Y132500D03*
X697248Y128000D03*
X719500Y185600D03*
X725000Y189000D03*
X720000Y849000D03*
X721900Y852750D03*
X730748Y99500D03*
X740000Y109534D03*
X732248Y140000D03*
X731716Y156500D03*
X736000Y142000D03*
X740000Y681000D03*
X740500Y755000D03*
X739900Y760000D03*
X757000Y435500D03*
X752100Y435600D03*
X751500Y431000D03*
X756500D03*
X757802Y474000D03*
X773000Y339500D03*
X761600Y435600D03*
X761500Y431000D03*
X766000D03*
X770000Y677000D03*
Y681500D03*
X767000Y845000D03*
X773000Y917000D03*
Y921500D03*
Y927000D03*
X767500D03*
X771000Y958500D03*
X766600D03*
X762100Y958600D03*
X771500Y963500D03*
X767100D03*
X762600Y963600D03*
X771400Y968900D03*
X767000D03*
X762500Y969000D03*
X777500Y339500D03*
X782400Y339400D03*
X782600Y411000D03*
X792000Y356500D03*
X801500Y573000D03*
X819000Y473000D03*
X829500Y373500D03*
Y380000D03*
Y385500D03*
X848600Y517100D03*
X843100Y517000D03*
X843200Y512800D03*
X843300Y507900D03*
X848800Y508000D03*
X848700Y512900D03*
X854500Y778000D03*
X850000D03*
X854500Y783000D03*
X850000D03*
X858500Y656500D03*
X879736Y290000D03*
X875500Y290500D03*
X878500Y294178D03*
X884000Y396500D03*
X879500D03*
X889000Y617000D03*
X895000Y96000D03*
X899500Y92500D03*
X899000Y405500D03*
X894000D03*
X899000Y410500D03*
X894000D03*
X895000Y617500D03*
X930500Y219000D03*
X936500D03*
X930500Y232000D03*
X936500D03*
Y225500D03*
X930500D03*
Y536500D03*
X943500Y488000D03*
X966000Y209500D03*
X961000Y212500D03*
X963500Y488000D03*
Y536500D03*
Y654500D03*
X958000D03*
Y659500D03*
X963500D03*
X969000Y655100D03*
Y659500D03*
X981000Y386500D03*
X985000Y388000D03*
X980500Y391000D03*
X984500Y392500D03*
X974500Y655100D03*
Y659500D03*
X1004500Y84000D03*
X1013500D03*
X1009000D03*
X1016500Y75500D03*
X1011500Y642000D03*
Y648000D03*
X1022500Y51500D03*
X1034500D03*
X1028000D03*
X1021000Y75500D03*
X1033000Y290000D03*
X1027500D03*
X1027700Y294200D03*
X1033200D03*
X1035500Y825500D03*
Y830000D03*
X1053000Y228000D03*
X1046000Y290000D03*
X1039500D03*
X1039700Y294200D03*
X1046200D03*
X1040000Y825500D03*
X1044500D03*
X1049000D03*
X1053400D03*
X1040000Y830000D03*
X1057000Y229500D03*
X1056716Y224500D03*
X1060000Y929500D03*
X1086000Y187500D03*
Y192500D03*
X1079000Y434000D03*
X1085000D03*
X1079100Y429000D03*
X1101500Y461500D03*
X1102500Y762500D03*
X1097500D03*
X1102500Y767400D03*
X1097500D03*
X1093000Y766500D03*
X1097500Y797500D03*
X1106600Y753000D03*
X1134000Y229000D03*
X1128500D03*
X1129000Y502500D03*
X1123500D03*
Y507500D03*
X1129000D03*
X1135500D03*
Y502500D03*
X1141000Y507500D03*
Y502500D03*
X1161500Y222000D03*
X1166500D03*
X1160500Y242000D03*
Y246500D03*
X1165000Y242000D03*
Y246500D03*
X1171000Y222000D03*
X1176000D03*
X1169000Y398000D03*
X1171000Y394000D03*
X1170500Y461000D03*
X1173100Y499200D03*
X1182000Y816000D03*
X1181500Y820500D03*
X1177000D03*
X1199100Y226600D03*
X1194900D03*
X1195000Y422500D03*
X1194000Y484000D03*
X1189500D03*
X1194000Y488500D03*
X1189500D03*
Y492900D03*
X1194000Y493000D03*
X1188500Y500000D03*
X1195920Y753700D03*
X1203500Y193800D03*
Y198000D03*
X1208000D03*
Y193800D03*
X1204000Y206000D03*
X1208500Y207000D03*
X1204000Y210500D03*
Y215000D03*
X1207500Y225000D03*
X1203300Y226600D03*
X1217000Y537000D03*
X1216500Y710125D03*
X1249300Y166000D03*
X1240600Y167000D03*
X1240700Y171200D03*
X1240800Y179800D03*
X1240700Y175500D03*
Y184000D03*
X1241000Y219000D03*
X1239500Y227500D03*
X1242000Y223500D03*
X1244000Y227500D03*
X1246000Y263500D03*
X1263000Y717000D03*
X1287500Y428000D03*
X1308500Y771500D03*
X1303000D03*
X1314000D03*
X1324500Y345400D03*
Y341000D03*
X1329000Y341100D03*
Y345500D03*
X1323000Y368000D03*
X1327500D03*
X1332000D03*
Y372400D03*
X1327500D03*
X1323000D03*
X1338000Y341100D03*
X1333500D03*
Y345500D03*
X1338000D03*
X1358500Y346500D03*
Y351000D03*
X1354000D03*
Y346500D03*
X1354500Y480500D03*
Y475000D03*
X1360500D03*
Y480500D03*
X1354500Y486500D03*
X1360500D03*
X1360000Y631500D03*
X1355500Y631000D03*
X1358000Y626000D03*
X1357500Y635500D03*
X1351000Y677000D03*
Y672000D03*
X1355000Y674500D03*
X1354500Y669000D03*
X1371500Y254000D03*
X1366000D03*
X1371500Y264000D03*
X1366000D03*
X1371500Y259500D03*
X1366000D03*
G54D22*
X180118Y729409D03*
Y739409D03*
X200118Y729409D03*
X190118D03*
X210118D03*
X220118D03*
X250118D03*
X240118D03*
G54D36*
X599941Y70118D03*
X607933D03*
X595905Y80118D03*
X603897D03*
X611889D03*
X615925Y70118D03*
X623917D03*
X627953Y80118D03*
X631909Y70118D03*
X639901D03*
X635945Y80118D03*
X643937D03*
G54D31*
X545079Y290355D03*
X560829D03*
X549014Y298230D03*
X556889Y308070D03*
X552954Y315945D03*
X549014Y308070D03*
X576574Y290355D03*
X564764Y298230D03*
X572639Y308070D03*
X568699Y315945D03*
X592324Y290355D03*
X580514Y298230D03*
X588384Y308070D03*
X584449Y315945D03*
X608069Y290355D03*
X596259Y298230D03*
X604134Y308070D03*
X600199Y315945D03*
X627754Y298230D03*
X623819Y290355D03*
X612009Y298230D03*
X619884Y308070D03*
X615944Y315945D03*
X643504Y298230D03*
X639569Y290355D03*
X635629Y308070D03*
X631694Y315945D03*
X659254Y298230D03*
X655314Y290355D03*
X651379Y308070D03*
X647439Y315945D03*
X674999Y298230D03*
X671064Y290355D03*
X667124Y308070D03*
X663189Y315945D03*
X690749Y298230D03*
X686809Y290355D03*
X682874Y308070D03*
X678939Y315945D03*
X706494Y298230D03*
X702559Y290355D03*
X698624Y308070D03*
X694684Y315945D03*
X722244Y298230D03*
X718309Y290355D03*
X726179Y315945D03*
X714369Y308070D03*
X710434Y315945D03*
X737994Y298230D03*
X734054Y290355D03*
X741929Y315945D03*
X730119Y308070D03*
X753739Y298230D03*
X749804Y290355D03*
X757679Y315945D03*
X745864Y308070D03*
X769489Y298230D03*
X765549Y290355D03*
X773424Y315945D03*
X761614Y308070D03*
X785234Y298230D03*
X781299Y290355D03*
X789174Y315945D03*
X777364Y308070D03*
X800984Y298230D03*
X797049Y290355D03*
X804919Y315945D03*
X793109Y308070D03*
X816734Y298230D03*
X812794Y290355D03*
X820669Y315945D03*
X808859Y308070D03*
X840354Y298230D03*
X836419Y290355D03*
X832479Y298230D03*
X840354Y308070D03*
X836419Y315945D03*
X832479Y308070D03*
X856104Y298230D03*
X852164Y290355D03*
X848229Y298230D03*
X844289Y290355D03*
X856104Y308070D03*
X852164Y315945D03*
X844289D03*
X871849Y298230D03*
X867914Y290355D03*
X863974Y298230D03*
X871849Y308070D03*
X867914Y315945D03*
X863974Y308070D03*
G54D39*
X1066929Y43267D03*
X1057086D03*
X1074803D03*
X1272441Y7087D03*
X1299213D03*
G54D41*
X1224016Y180709D03*
G54D24*
X200000Y401500D03*
Y411500D03*
Y421500D03*
X216500Y401500D03*
Y411500D03*
Y421500D03*
X945197Y380000D03*
X968819D03*
X1296000Y319500D03*
Y329500D03*
X1367067Y42323D03*
Y78544D03*
X1392657Y42323D03*
Y78544D03*
G54D28*
X402953Y23622D03*
X413189D03*
X423425D03*
G54D33*
X590315Y9134D03*
Y19134D03*
X649527Y9134D03*
Y19134D03*
Y29134D03*
G54D15*
X35435Y373228D03*
X82675D03*
G54D44*
X1272677Y349016D03*
G54D29*
X404920Y330117D03*
X412794D03*
X412815Y349860D03*
X408857Y341928D03*
Y365550D03*
Y357676D03*
Y385237D03*
Y377363D03*
Y400985D03*
Y393111D03*
Y416733D03*
Y408859D03*
Y424607D03*
X420668Y330117D03*
X424605Y345865D03*
Y369487D03*
Y361613D03*
Y353739D03*
Y385237D03*
X428542Y400985D03*
X424605D03*
Y393111D03*
X428542Y397048D03*
X420668Y400985D03*
X428523Y416683D03*
X416731Y416733D03*
Y404922D03*
X423555Y431500D03*
X416731Y420670D03*
Y424607D03*
X430513Y320841D03*
X440353Y349802D03*
X444290D03*
X440353Y341928D03*
X436416Y345865D03*
X440353Y369487D03*
X444290Y365550D03*
X440353Y353739D03*
X444290Y357676D03*
X432479Y369487D03*
Y361613D03*
X444290Y385237D03*
Y377363D03*
X440353Y381300D03*
X432479Y385237D03*
X436416Y377363D03*
X432479D03*
X440353Y400985D03*
Y389174D03*
X432479Y400985D03*
Y397048D03*
Y393111D03*
Y389174D03*
X444323Y416883D03*
X436523Y416683D03*
X442535Y426770D03*
X434723Y426283D03*
X456103Y330117D03*
X460040Y349802D03*
Y341928D03*
X448227Y349802D03*
X456103Y365550D03*
Y357676D03*
X460040Y369487D03*
Y361613D03*
X448227Y369487D03*
Y361613D03*
Y353739D03*
X456103Y385237D03*
Y377363D03*
X460040Y381300D03*
X448227D03*
X460040Y389174D03*
X448227D03*
X456103Y400985D03*
X460040D03*
X456103Y393111D03*
X460040D03*
Y397048D03*
X448227Y400985D03*
Y393111D03*
X456103Y412796D03*
X460023Y408883D03*
X450725Y425460D03*
X471851Y322243D03*
Y326180D03*
X463977Y330117D03*
X475788Y349802D03*
Y341928D03*
X467914Y349802D03*
X475788Y369487D03*
Y361613D03*
Y357676D03*
X467914Y369487D03*
Y361613D03*
Y365550D03*
Y357676D03*
Y353739D03*
X463977Y365550D03*
Y357676D03*
Y385237D03*
X475788Y381300D03*
Y377363D03*
X467914Y385237D03*
Y377363D03*
Y381300D03*
X463977Y377363D03*
X475788Y400985D03*
Y397048D03*
Y393111D03*
X471851D03*
Y397048D03*
X475788Y389174D03*
X467914Y400985D03*
Y397048D03*
Y393111D03*
Y389174D03*
X463977Y393111D03*
Y397048D03*
X471851Y412796D03*
X475788Y424607D03*
X493855Y312700D03*
X488155Y315700D03*
X490455Y319200D03*
X481255Y320000D03*
X491536Y334054D03*
X479725Y330117D03*
X479655Y322500D03*
X491536Y341928D03*
X479725Y337991D03*
Y369487D03*
Y361613D03*
X487643Y361523D03*
X491500Y353500D03*
X491536Y385237D03*
Y377363D03*
X479725Y381300D03*
X491536Y400985D03*
Y393111D03*
X479725Y397048D03*
Y389174D03*
X491536Y416733D03*
Y408859D03*
X487599Y416733D03*
X483662Y408859D03*
X487599Y404922D03*
X479725Y412796D03*
X491536Y420670D03*
Y424607D03*
X483662D03*
X487599D03*
X505678Y310921D03*
X506000Y317500D03*
X498855Y311100D03*
X498955Y316900D03*
X505523Y332086D03*
X499410Y322243D03*
X511500Y348000D03*
X511455Y338700D03*
X505523Y363582D03*
X507955Y356100D03*
X505523Y371456D03*
X503347Y381300D03*
Y397048D03*
Y389174D03*
X499410Y416733D03*
Y412796D03*
Y408859D03*
X503347D03*
Y404922D03*
X495473Y416733D03*
Y412796D03*
Y408859D03*
X499410Y420670D03*
Y424607D03*
X503347Y420670D03*
X495473Y424607D03*
Y420670D03*
X1020500Y882500D03*
Y887000D03*
X1011966Y893534D03*
X1020282Y911218D03*
X1034000Y155000D03*
X1021468Y866968D03*
X1032600Y867657D03*
X1031500Y884500D03*
X1035216Y884468D03*
X1035000Y888500D03*
Y880500D03*
Y970000D03*
X1039468Y155284D03*
X1048968D03*
X1053500Y153000D03*
X1044000D03*
X1048968Y150784D03*
X1039500Y151000D03*
X1048968Y159284D03*
X1039500Y159500D03*
X1053500Y157500D03*
X1044000D03*
X1045968Y185500D03*
X1039000Y884500D03*
X1051000Y883600D03*
Y888500D03*
X1065000Y154000D03*
X1057968Y155284D03*
X1058000Y150500D03*
Y159500D03*
X1060509Y177126D03*
X1058000Y889500D03*
Y902500D03*
Y896000D03*
X1055000Y970000D03*
X1084988Y154203D03*
X1080500Y153500D03*
X1077500Y150000D03*
X1085150Y158400D03*
X1075000Y970000D03*
X1105000D03*
X1125000D03*
X1145000D03*
X1175000D03*
X1195000D03*
X1215000D03*
X1259968Y444284D03*
X1260000Y448500D03*
X1264500Y446500D03*
X1260000Y440000D03*
X1264500Y442000D03*
X1257468Y478500D03*
X1278500Y448500D03*
Y444000D03*
X1274000Y447000D03*
X1269468Y444284D03*
Y448284D03*
X1278500Y439500D03*
X1269468Y439784D03*
X1274000Y442000D03*
X1270000Y477000D03*
X1288000Y442000D03*
X1292500Y441000D03*
X1318000Y369500D03*
Y375500D03*
Y381500D03*
X1330000Y428000D03*
X1331500Y432500D03*
X1344000Y434500D03*
X1340200D03*
Y438300D03*
X1343900Y438500D03*
X1343000Y466500D03*
G54D10*
X8590Y318590D03*
X4500Y329297D03*
Y349297D03*
Y369297D03*
Y389297D03*
Y409297D03*
Y429297D03*
Y449297D03*
Y469297D03*
Y489297D03*
Y509297D03*
Y529297D03*
Y549297D03*
Y569297D03*
Y589297D03*
Y609297D03*
Y629297D03*
Y649297D03*
Y669297D03*
Y689297D03*
Y709297D03*
Y729297D03*
Y749297D03*
Y769297D03*
Y789297D03*
Y809297D03*
Y829297D03*
Y849297D03*
X8442Y847311D03*
X4500Y869297D03*
Y889297D03*
Y909297D03*
Y929297D03*
Y949297D03*
Y969297D03*
X20000Y380000D03*
Y440000D03*
Y460000D03*
Y480000D03*
Y500000D03*
X50395Y384679D03*
X40945Y384710D03*
X48820Y412435D03*
X39370Y412673D03*
X40054Y823970D03*
X36004Y839500D03*
X38804Y906220D03*
X41500Y941500D03*
X46500Y944500D03*
X59840Y384679D03*
X67715Y412518D03*
X58270Y412485D03*
X60304Y663220D03*
X64304Y698720D03*
X63304Y706720D03*
X64272Y736004D03*
X55304Y849720D03*
X78740Y384915D03*
X69290Y384865D03*
X77165Y412590D03*
X76804Y662720D03*
X73804Y699720D03*
X81304Y710220D03*
X76272Y762504D03*
X77804Y773720D03*
X71804Y789720D03*
X73772Y822004D03*
X69804Y835720D03*
X83838Y848133D03*
X76804Y847720D03*
X81804Y888720D03*
X72770Y906488D03*
X95304Y663720D03*
X97737Y698653D03*
X96060Y762476D03*
X100804Y774720D03*
X99804Y799720D03*
X85804Y816220D03*
X87804Y835720D03*
X98304Y888220D03*
X97804Y940720D03*
X112654Y314453D03*
X111304Y663720D03*
X111907Y698617D03*
X115804Y798720D03*
X101804Y940720D03*
X112900Y988500D03*
X132500Y312500D03*
X124500Y316000D03*
X122874Y354709D03*
X132804Y894220D03*
X134874Y354709D03*
X147374D03*
X149100Y661100D03*
X143010Y676400D03*
X162595Y296709D03*
X153437Y320458D03*
X155874Y310209D03*
X152995Y329119D03*
X159674Y328609D03*
X159774Y320709D03*
X158874Y354709D03*
X163225Y522080D03*
X154755Y539310D03*
X166875Y678285D03*
X153500Y690275D03*
X163000Y901000D03*
X158000D03*
X172285Y296964D03*
X181889Y297303D03*
X183374Y328709D03*
X171874D03*
X171295Y320709D03*
X180315Y321209D03*
X170374Y354709D03*
X170339Y537396D03*
X180555Y560500D03*
X175055Y569500D03*
X172040Y688960D03*
X181000Y901000D03*
X174500Y901500D03*
X168500Y901000D03*
X197245Y296571D03*
X196063Y319209D03*
X192874Y326209D03*
Y337907D03*
X189000Y347600D03*
X192500Y431500D03*
X190800Y462800D03*
X189355Y526470D03*
X195725Y540750D03*
X198000Y785000D03*
X191875Y803125D03*
X188000Y901000D03*
X197000D03*
Y897000D03*
X207086Y297418D03*
X205511Y320709D03*
X214960Y321044D03*
X212500Y435000D03*
X208305Y562640D03*
X201000Y625500D03*
X212500Y786000D03*
X204500Y817500D03*
X205500Y901000D03*
Y897000D03*
X217295Y296709D03*
X232500Y419000D03*
Y431000D03*
X231500Y898500D03*
X242500Y565500D03*
X240000Y829250D03*
X236500Y866000D03*
X261500Y188900D03*
X256300Y188800D03*
X258800Y184200D03*
X261400Y179800D03*
X255800Y179600D03*
X258500Y608500D03*
Y613500D03*
X253500Y608500D03*
X253555Y613500D03*
X261500Y857500D03*
X262178Y976000D03*
X261178Y981040D03*
X268300Y219800D03*
X273000Y674000D03*
X269000Y921500D03*
X274000D03*
X273678Y958000D03*
X268178Y955500D03*
X297929Y332000D03*
Y336000D03*
X293929Y342000D03*
X285678Y995500D03*
X293178D03*
X299500Y5500D03*
X299300Y84200D03*
X311500Y153000D03*
X299000Y148000D03*
X307129Y143000D03*
X305029Y147700D03*
X304300Y160200D03*
X304100Y167000D03*
X311300D03*
X312500Y159100D03*
X305429Y219400D03*
Y223000D03*
X311500Y272000D03*
X307500Y299000D03*
X303545Y445840D03*
X300112Y483783D03*
X305155Y504900D03*
X305255Y542600D03*
X301178Y995500D03*
X309678D03*
X321000Y29000D03*
Y33500D03*
Y38000D03*
Y57000D03*
Y52500D03*
Y48000D03*
Y42500D03*
Y61500D03*
X316900Y65900D03*
X320500Y66000D03*
X330250Y80000D03*
X317660Y96400D03*
X330900Y134500D03*
X329929Y128500D03*
X325929Y127700D03*
X319014Y152977D03*
X328700Y154400D03*
X328629Y146800D03*
X330400Y141600D03*
X318200Y159100D03*
X329929Y241500D03*
X316000Y271500D03*
X326000Y292500D03*
X327000Y308000D03*
X331000Y308018D03*
X322429Y349300D03*
X320238Y497183D03*
X316273Y520282D03*
X321555Y534500D03*
X315135Y554980D03*
X324678Y995500D03*
X317178D03*
X336700Y4300D03*
X341200D03*
X346000Y4400D03*
X338000Y127500D03*
X337400Y134500D03*
X334000Y147600D03*
X345929Y183000D03*
X340679Y204900D03*
X332429Y210000D03*
X346404Y260000D03*
X344429Y312000D03*
X341500Y309500D03*
X345929Y336500D03*
X341351Y336434D03*
X335645Y445630D03*
X343095Y446200D03*
X338595Y482590D03*
X339140Y512500D03*
X336445Y509330D03*
X343555Y517000D03*
X340715Y545840D03*
X339500Y936500D03*
X333500Y954000D03*
X341178Y996000D03*
X332678Y995500D03*
X355000Y4400D03*
X350500D03*
X360400D03*
X362500Y64000D03*
X352500Y113000D03*
X357394Y131496D03*
X348429Y130000D03*
X353929Y128500D03*
X351429Y126500D03*
X362009Y142520D03*
Y148819D03*
Y155119D03*
X362036Y170876D03*
X362034Y161406D03*
X353085Y187485D03*
X355040Y180000D03*
X362017Y183492D03*
X354540Y199000D03*
X353300Y218400D03*
X352429Y279000D03*
X357929Y277000D03*
X348000Y292500D03*
X357055Y385000D03*
Y380500D03*
Y376500D03*
X355055Y394000D03*
Y389500D03*
X364055Y512000D03*
X351815Y546880D03*
X364000Y869500D03*
X358268Y995500D03*
X348678Y996000D03*
X364900Y4400D03*
X369400D03*
X370000Y51000D03*
Y55500D03*
Y60000D03*
X368307Y133071D03*
X374606Y136221D03*
X371458Y142520D03*
X377765Y155146D03*
X374589Y155110D03*
X371455Y148854D03*
X377787Y148812D03*
X365186Y170876D03*
X377732Y167703D03*
X377718Y161417D03*
X371470Y167741D03*
X371489Y161411D03*
X365186Y177175D03*
X368320Y183460D03*
X377741Y177188D03*
X377731Y180302D03*
X371457Y173978D03*
X368336Y189755D03*
X368307Y196062D03*
Y202361D03*
X377755D03*
Y199211D03*
Y196062D03*
Y192912D03*
Y189763D03*
X374607Y218110D03*
X374606Y211810D03*
X366000Y277500D03*
X372055Y319500D03*
X369555Y322500D03*
X371555Y347500D03*
X375805Y380250D03*
X371781Y387924D03*
X373555Y482500D03*
X367555Y545500D03*
X380000Y872000D03*
X371938Y922438D03*
X377953Y995725D03*
X390354Y136221D03*
X380906Y136220D03*
X384055Y155117D03*
X396653D03*
X380907Y142520D03*
X387206Y145670D03*
X390355Y142520D03*
X393505Y145670D03*
X384093Y151968D03*
X393519Y151990D03*
X384055Y158266D03*
X396653D03*
X390354Y167715D03*
X396653D03*
X384032Y167703D03*
X380944Y161417D03*
X387219Y158290D03*
X390392Y186614D03*
X384055Y186613D03*
X396654Y186614D03*
X396653Y174015D03*
Y180314D03*
X387204Y177164D03*
X384032Y174003D03*
X384055Y202361D03*
X393503Y205510D03*
X396654Y202362D03*
X396653Y205511D03*
Y199211D03*
X384055Y192912D03*
Y196062D03*
X396653Y192912D03*
X393503Y211809D03*
X380906Y211810D03*
X396654D03*
X396653Y208660D03*
X393503D03*
X390354Y218109D03*
Y221259D03*
Y224408D03*
X391000Y238500D03*
X394929Y247000D03*
X386755Y447300D03*
X396055Y456500D03*
X389000Y604000D03*
X395500Y867000D03*
X396500Y910500D03*
X383500Y938500D03*
X389763Y996085D03*
X402950Y133050D03*
X399835Y139375D03*
X412429Y136210D03*
X412415Y148794D03*
X399779Y142531D03*
X399804Y145670D03*
X412403Y142520D03*
X406102Y155117D03*
X412402Y155118D03*
X412401Y151967D03*
X399819Y151950D03*
X406125Y148804D03*
X402952Y167715D03*
X409251D03*
X412401Y158267D03*
X406102D03*
X402977Y174003D03*
X402952Y186613D03*
X409251D03*
X409288Y180315D03*
X402952Y180314D03*
X409251Y174015D03*
X412401Y205510D03*
X402952Y192912D03*
X409251D03*
X402953Y211810D03*
X412402D03*
X399803Y218109D03*
Y221259D03*
Y208660D03*
X409929Y245400D03*
X412513Y294800D03*
X398385Y292540D03*
X401555Y318000D03*
X410500Y885500D03*
X401500Y994500D03*
X415549Y151990D03*
X418702Y142520D03*
X425001D03*
X428149Y164565D03*
Y170865D03*
X421876Y167705D03*
X415575Y167703D03*
X424999Y161416D03*
X428149Y183463D03*
Y177164D03*
X421876Y174005D03*
Y180304D03*
Y186603D03*
X415551Y186614D03*
X415587Y180315D03*
X415551Y174015D03*
X424999Y199211D03*
X428149D03*
X424999Y202361D03*
X428149D03*
X421876Y192902D03*
X428149Y192912D03*
X415551D03*
X418701Y211810D03*
X425001D03*
X420429Y246400D03*
X416500Y284800D03*
X422500Y271501D03*
X428542Y330117D03*
X425178Y798000D03*
X418278Y828000D03*
Y840000D03*
X418500Y857500D03*
X418278Y854000D03*
Y846500D03*
X419500Y914000D03*
X425000Y994500D03*
X430540Y108750D03*
X434449Y155118D03*
X431300Y142520D03*
X437599D03*
X431299Y164565D03*
Y170865D03*
X434449Y167716D03*
Y161417D03*
X431299Y161416D03*
Y183463D03*
X434449Y180314D03*
Y174015D03*
X431299Y177164D03*
X434448Y186613D03*
X431299D03*
X434414Y205514D03*
X434449Y199212D03*
Y192913D03*
Y211810D03*
X436500Y241000D03*
X439000Y254500D03*
X440500Y267000D03*
X444255Y283700D03*
X430900Y294550D03*
X436416Y330117D03*
X444290D03*
X436416Y357676D03*
X432178Y798000D03*
X438178Y798500D03*
X444678Y798400D03*
X442278Y846000D03*
X431500Y886000D03*
X437678D03*
X443178D03*
X435678Y996000D03*
X443178D03*
X457500Y121000D03*
X457429Y171500D03*
X458429Y185000D03*
X459500Y290100D03*
X448227Y341928D03*
X458685Y425710D03*
X456178Y798000D03*
X452978Y805400D03*
X455278Y846000D03*
X451278D03*
X459278D03*
X451178Y886000D03*
X460678D03*
X457578Y879700D03*
X458678Y996000D03*
X450178D03*
X471429Y133500D03*
X465679Y192600D03*
X469155Y297800D03*
X474755Y308300D03*
X466655Y425340D03*
X472055Y425000D03*
X475678Y798500D03*
X463178D03*
X469178D03*
X467278Y846000D03*
X468178Y886000D03*
X472178D03*
X474178Y995500D03*
X466178Y996000D03*
X481929Y126500D03*
X490100Y162100D03*
X492555Y431250D03*
X482178Y886000D03*
X489678Y995500D03*
X482178D03*
X503929Y127500D03*
X499629Y178400D03*
X498855Y302851D03*
X495555Y369500D03*
X507355Y390800D03*
X497778Y843000D03*
Y838500D03*
Y847000D03*
X498500Y867500D03*
X505678Y995500D03*
X498178D03*
X525679Y136250D03*
X517679Y125750D03*
X513407Y311502D03*
X513500Y315800D03*
X522345Y311699D03*
X522365Y316365D03*
X521800Y322000D03*
X527667Y322182D03*
X523500Y347500D03*
Y352000D03*
Y342000D03*
X523100Y364300D03*
X526800Y359600D03*
X519500Y365500D03*
X523500Y357500D03*
X521500Y632500D03*
X521178Y995500D03*
X513678D03*
X538875Y138000D03*
X542000Y249000D03*
X528600Y316700D03*
X539300Y317600D03*
X534000Y317500D03*
X539200Y324100D03*
X530000Y342000D03*
X529400Y352800D03*
X530100Y347200D03*
X536678Y996000D03*
X530083Y995500D03*
X546500Y147500D03*
X547500Y360168D03*
X560678Y996000D03*
X577000Y58000D03*
X568500Y147500D03*
X574000Y269000D03*
X563250Y262500D03*
X571555Y326000D03*
X562055Y347500D03*
X567500Y457500D03*
X563000Y453000D03*
X567500D03*
Y462000D03*
Y466500D03*
X563000Y457500D03*
Y462000D03*
Y466500D03*
X569178Y996000D03*
X576678D03*
X579221Y237250D03*
X580828Y260028D03*
X584678Y994500D03*
X604500Y205000D03*
Y200500D03*
X603500Y218500D03*
Y214000D03*
X594500Y236000D03*
X610500Y333000D03*
X606000Y341500D03*
X609000Y345500D03*
X598178Y983500D03*
X615000Y333000D03*
X620500D03*
X611500Y341500D03*
X613500Y345500D03*
X616500Y341500D03*
X621500D03*
X642000Y335000D03*
X639000Y332000D03*
X638500Y409000D03*
X634500Y427000D03*
X637000Y431500D03*
X632500D03*
X637000Y436500D03*
X632500D03*
X641625Y465375D03*
X628250Y570200D03*
X646500Y101000D03*
X650500D03*
X651500Y408500D03*
X646500D03*
X647125Y429375D03*
X656162Y472338D03*
X654500Y494000D03*
X647252Y576500D03*
X662248Y101000D03*
X670454Y94544D03*
X667748Y104000D03*
X670522Y130200D03*
X673500Y334000D03*
X668000D03*
X662000D03*
X663500Y452000D03*
X672500D03*
X660000Y443500D03*
X663500Y456000D03*
Y460500D03*
X667500Y454000D03*
Y458500D03*
X672500Y456000D03*
Y460500D03*
X690966Y142028D03*
X687055Y258500D03*
X683055D03*
X678055D03*
X681000Y452000D03*
X690500Y468000D03*
X681000Y456000D03*
Y460500D03*
X676500Y454000D03*
Y458500D03*
X690000Y460500D03*
X687968Y755284D03*
Y781784D03*
X700000Y60500D03*
X703053Y133568D03*
X704716Y156520D03*
X700216Y156368D03*
X706055Y258500D03*
X705500Y352500D03*
X707000Y340500D03*
X708500Y365000D03*
X707000Y385000D03*
Y378000D03*
X708500Y371000D03*
X694000Y483500D03*
X693500Y472000D03*
X694000Y492000D03*
Y500500D03*
Y507500D03*
Y514000D03*
X705900Y569200D03*
X698818Y759350D03*
X703328Y800144D03*
X697250Y876750D03*
X715716Y82652D03*
X713716Y121284D03*
X721716Y112784D03*
Y116784D03*
X717716Y121284D03*
X721716D03*
Y129284D03*
Y125284D03*
X722716Y156520D03*
X718216D03*
X713716D03*
X709216D03*
X721200Y205800D03*
X710055Y258500D03*
X714055D03*
X711500Y385000D03*
Y378000D03*
X720500Y478750D03*
X723168Y774984D03*
X712500Y859750D03*
X716250Y860250D03*
X723000Y996500D03*
X729716Y121284D03*
X725716D03*
X727248Y141500D03*
X727216Y156520D03*
X733498Y180750D03*
X733000Y193000D03*
X732500Y485500D03*
X734500Y547500D03*
X734462Y553538D03*
X733268Y757984D03*
X735000Y780500D03*
X727468Y819284D03*
X733440Y875560D03*
X731498Y996500D03*
X739368Y996610D03*
X727558Y996500D03*
X757200Y103100D03*
X746716Y130238D03*
X750916Y130272D03*
X745500Y145000D03*
X756000Y180000D03*
X749750Y454000D03*
X755300Y489300D03*
X746750Y571750D03*
X748000Y579500D03*
X745400Y877600D03*
X761000Y88500D03*
Y82500D03*
X760600Y94500D03*
X760522Y116784D03*
X770000Y123500D03*
X770500Y136000D03*
X770900Y144300D03*
X765116Y187659D03*
X771000Y464000D03*
X765009Y563491D03*
X760125Y666875D03*
X770646Y685354D03*
X777500Y351000D03*
X782500D03*
X788600Y449300D03*
X784800D03*
X776468Y447600D03*
X784900Y453000D03*
X788800D03*
X784274Y486274D03*
X790600Y547600D03*
X790000Y554500D03*
X785500Y666500D03*
X783746Y692754D03*
X787500Y783500D03*
X782750Y845750D03*
X781000Y877000D03*
X776750Y964750D03*
X806274Y434726D03*
X791000Y562000D03*
X802500Y579500D03*
X794000Y723500D03*
X791500Y783500D03*
X805250Y865750D03*
X794500Y897000D03*
X800500Y977500D03*
X794500D03*
X800500Y982000D03*
X794500D03*
X818500Y361600D03*
X813500Y367000D03*
X811000Y430500D03*
X810000Y735500D03*
X814000Y849500D03*
X810000Y980000D03*
X838055Y262500D03*
X828500Y361500D03*
X837000D03*
X825500Y411100D03*
X832500Y404000D03*
X826500Y436000D03*
X826000Y465078D03*
X831000Y598500D03*
X839250Y854500D03*
X826060Y863440D03*
X840000Y980000D03*
X847055Y262500D03*
X851555D03*
X854820Y352380D03*
X846500Y362000D03*
X842000Y367000D03*
Y372000D03*
Y377500D03*
X852000Y401500D03*
X842000D03*
X847000Y396500D03*
Y401500D03*
Y406500D03*
X854000Y436500D03*
X846250Y642250D03*
X854000Y640500D03*
X852500Y710500D03*
X842500Y719500D03*
X852600Y868500D03*
X872000Y75500D03*
X866112Y85626D03*
X865055Y262500D03*
X871500Y484000D03*
X871000Y639500D03*
X870500Y665060D03*
X861250Y649250D03*
X865500Y690500D03*
X860500Y734000D03*
X870000Y980000D03*
X888750Y324660D03*
X884120Y351630D03*
X877000Y409500D03*
X874450Y463500D03*
X877500Y612500D03*
X884200Y636500D03*
X878500Y695500D03*
X902000Y63000D03*
X904600Y406600D03*
X900000Y980000D03*
X935000Y51500D03*
X937000Y63000D03*
X936000Y373500D03*
X934000Y448700D03*
X968085Y452065D03*
X980078Y204578D03*
X980960Y195257D03*
X989000Y66500D03*
X996500Y167000D03*
X988660Y190500D03*
X998000Y461500D03*
X1002500Y520000D03*
X994500Y543800D03*
X1001000Y771500D03*
X1007000Y12000D03*
X1012000Y43000D03*
X1017274Y219274D03*
X1013000Y282500D03*
X1012900Y275300D03*
X1007500Y487500D03*
X1016500Y519500D03*
X1008500Y543700D03*
X1007032Y879968D03*
X1010000Y980000D03*
X1032000Y82500D03*
Y90000D03*
Y97000D03*
Y103500D03*
Y110000D03*
X1036019Y203177D03*
X1036000Y199500D03*
X1035922Y209578D03*
X1031800Y248800D03*
X1027500Y248500D03*
X1036300Y248800D03*
X1042500Y930000D03*
X1040000Y980000D03*
X1066500Y185500D03*
X1060000Y207500D03*
X1060500Y282500D03*
X1060600Y303150D03*
X1056100Y303200D03*
X1059900Y295200D03*
X1059800Y290600D03*
X1061696Y761294D03*
X1061356Y753354D03*
X1071000Y71000D03*
X1077250Y102000D03*
X1077500Y97000D03*
Y107500D03*
X1086000Y126500D03*
X1074500Y185500D03*
X1072500Y208924D03*
X1074500Y627500D03*
X1073000Y637500D03*
X1071500Y739000D03*
X1077500Y759000D03*
X1085468Y895968D03*
X1070000Y980000D03*
X1088000Y85500D03*
X1098000Y126500D03*
X1102000Y250000D03*
X1102500Y264500D03*
X1089500Y405000D03*
X1088400Y647484D03*
X1098000Y775000D03*
X1093000Y791000D03*
X1097500Y784500D03*
X1098500Y823344D03*
X1092718Y859984D03*
X1093468Y896968D03*
X1100000Y980000D03*
X1113500Y614250D03*
X1113000Y630500D03*
X1105000D03*
X1110790Y738850D03*
X1107000Y757500D03*
X1114500Y855500D03*
X1119000D03*
X1118034Y847034D03*
X1113768D03*
X1116468Y870284D03*
Y874284D03*
Y865784D03*
X1112468Y870284D03*
X1114500Y886000D03*
X1103000Y888300D03*
X1118500Y886000D03*
X1123000Y250500D03*
X1120600Y282300D03*
X1126000Y618000D03*
X1122985Y670262D03*
X1122938Y676540D03*
X1119265Y683864D03*
X1135551Y685967D03*
X1135570Y711218D03*
X1132398Y720624D03*
X1132960Y752950D03*
X1126210Y752810D03*
X1134245Y769145D03*
X1127945Y769970D03*
X1121215Y769936D03*
X1135000Y810000D03*
X1134244Y799984D03*
X1121000Y808500D03*
X1127945Y799935D03*
X1121646Y799924D03*
X1121000Y823500D03*
X1123500Y832470D03*
X1135500Y835000D03*
X1135468Y854032D03*
X1120468Y870284D03*
X1131275Y867725D03*
X1130000Y980000D03*
X1145800Y282284D03*
X1151500Y449000D03*
X1147000Y619000D03*
X1151337Y660807D03*
X1141868Y680064D03*
X1151337Y670256D03*
X1151300Y682854D03*
Y692303D03*
Y689153D03*
Y686004D03*
Y695452D03*
X1148150D03*
Y692303D03*
Y689153D03*
Y686004D03*
Y682854D03*
X1151300Y698602D03*
X1148150D03*
X1145265Y776945D03*
X1151592Y773748D03*
X1140650Y782496D03*
X1151565Y787951D03*
X1142110Y792660D03*
X1149400Y800000D03*
X1142010Y809500D03*
X1137000Y890000D03*
X1144500D03*
X1152000D03*
X1166000Y232000D03*
X1162468Y257968D03*
X1168000Y302500D03*
X1166000Y290000D03*
X1168076Y310046D03*
X1152500Y311000D03*
X1158000Y309500D03*
X1152500Y318500D03*
X1160000D03*
X1167000Y321000D03*
Y326450D03*
X1155000Y594500D03*
X1165476Y613393D03*
X1152500Y608500D03*
X1165672Y609672D03*
X1159100Y640800D03*
X1154218Y679964D03*
X1154496Y667096D03*
X1160748Y682854D03*
X1157599Y686004D03*
X1154449D03*
Y682854D03*
Y689153D03*
X1160748Y695452D03*
X1157599D03*
Y692303D03*
X1154449Y695452D03*
Y692303D03*
X1163898Y695452D03*
X1160748Y692303D03*
X1163898D03*
X1157599Y689153D03*
X1160748D03*
X1163898D03*
X1160748Y686004D03*
X1163898D03*
Y698602D03*
X1160748D03*
X1157599D03*
X1154449D03*
X1166100Y731500D03*
X1152023Y733299D03*
X1160333Y753600D03*
X1167320Y770290D03*
X1157871Y773728D03*
X1167330Y795830D03*
X1163605Y783513D03*
X1167277Y792658D03*
X1157866Y795844D03*
X1165300Y809610D03*
X1160300D03*
X1154300D03*
X1155390Y818000D03*
X1157990Y827000D03*
X1158000Y890000D03*
X1164500D03*
X1155000Y980000D03*
X1171000Y232000D03*
X1177500Y290000D03*
X1174752Y320504D03*
X1175000Y327000D03*
X1176500Y383500D03*
X1182500Y407000D03*
X1179934Y567000D03*
X1176496Y698564D03*
X1179671Y698565D03*
X1184750Y781000D03*
X1170300Y809610D03*
X1186500Y232000D03*
X1196334Y290561D03*
X1185283Y290513D03*
X1198000Y348000D03*
X1192000Y344500D03*
X1197000Y372500D03*
X1187500Y411000D03*
X1197000Y409500D03*
X1185945Y695415D03*
X1196000Y710500D03*
X1188000Y762500D03*
X1198718Y800782D03*
X1188875Y856625D03*
X1185000Y980000D03*
X1208500Y202000D03*
X1209000Y212500D03*
X1208000Y231000D03*
X1201922Y248500D03*
X1202177Y260000D03*
X1208500Y283500D03*
X1208000Y271499D03*
Y297638D03*
Y309000D03*
X1206500Y330000D03*
X1208500Y321500D03*
X1203500Y345000D03*
X1208500Y346400D03*
Y359000D03*
X1208000Y371000D03*
X1209000Y438500D03*
X1209500Y561910D03*
X1215500Y605300D03*
X1203500Y698520D03*
X1210500Y733500D03*
X1201968Y757500D03*
X1212840Y781000D03*
X1204000Y862000D03*
X1217250Y862250D03*
X1211500Y882500D03*
X1215000Y980000D03*
X1225500Y714500D03*
X1230500Y841000D03*
X1239500Y204000D03*
Y214000D03*
X1239000Y251500D03*
X1241777Y265700D03*
X1241377Y274900D03*
X1238500Y290000D03*
X1239000Y302437D03*
X1238500Y316500D03*
X1250158Y326463D03*
X1238500Y325985D03*
X1239000Y338900D03*
Y352800D03*
X1239500Y366000D03*
X1234177Y379500D03*
X1243000Y446650D03*
X1249000Y723250D03*
X1248500Y775500D03*
X1248950Y782450D03*
X1245650Y821850D03*
X1245000Y980000D03*
X1256500Y166500D03*
X1261000D03*
X1265000Y169000D03*
Y174000D03*
X1258000Y205000D03*
X1265000Y211500D03*
X1261000Y207500D03*
Y211500D03*
X1251500Y266500D03*
X1251700Y274000D03*
X1254203Y282770D03*
X1261000Y292500D03*
X1261006Y303543D03*
X1252564Y290566D03*
X1253500Y316500D03*
Y305000D03*
X1257000Y311000D03*
X1258562Y672438D03*
X1259000Y699500D03*
X1257500Y710500D03*
X1259500Y724000D03*
X1264000Y853000D03*
X1281000Y475000D03*
X1276500D03*
X1271000Y573500D03*
Y568500D03*
X1282500Y598000D03*
Y645000D03*
X1282300Y678000D03*
X1276000Y694000D03*
X1272700Y694900D03*
X1277000Y712500D03*
X1272500D03*
X1275000Y732000D03*
X1277500Y757500D03*
Y778500D03*
X1267500Y779000D03*
X1275000Y980000D03*
X1290874Y34376D03*
X1295500Y291500D03*
X1285500Y475000D03*
X1293500D03*
X1297500Y562000D03*
X1286500Y569000D03*
X1291500Y666000D03*
X1298034Y907034D03*
X1309500Y51000D03*
X1311000Y435000D03*
X1307900Y577412D03*
X1306617Y587512D03*
X1308817Y595412D03*
X1311000Y651900D03*
X1306000Y782500D03*
X1314284D03*
X1304500Y838000D03*
X1300784Y838716D03*
X1303750Y862250D03*
X1307468Y884532D03*
X1300000Y980000D03*
X1331000Y120000D03*
X1322000Y318500D03*
X1319400Y522100D03*
X1318700Y533500D03*
X1323117Y626412D03*
X1329468Y666468D03*
X1318784Y793716D03*
X1321466Y907034D03*
X1330000Y980000D03*
X1347000Y88000D03*
X1347500Y116000D03*
X1334500Y557000D03*
X1344617Y588712D03*
Y593412D03*
X1346617Y626912D03*
X1342367Y627662D03*
X1333468Y680000D03*
X1354500Y276000D03*
X1358500Y288916D03*
X1354900Y522600D03*
X1355900Y536600D03*
X1355500Y556500D03*
X1360817Y557812D03*
X1349317Y593412D03*
X1353117Y610412D03*
X1363100Y627000D03*
X1349817Y628612D03*
X1360000Y980000D03*
X1369720Y106365D03*
X1375500Y328000D03*
X1378500Y370000D03*
Y365000D03*
Y360000D03*
X1377000Y384000D03*
Y379000D03*
X1378500Y374500D03*
X1377000Y390000D03*
X1374500Y395000D03*
Y402000D03*
X1372500Y415000D03*
X1368000Y450500D03*
X1369617Y557012D03*
X1378800Y594900D03*
X1390004Y106000D03*
G54D45*
X1338526Y29526D03*
G54D32*
X545079Y315945D03*
X556889Y298230D03*
X552954Y290355D03*
X560829Y315945D03*
X572639Y298230D03*
X568699Y290355D03*
X576574Y315945D03*
X564764Y308070D03*
X588384Y298230D03*
X584449Y290355D03*
X592324Y315945D03*
X580514Y308070D03*
X604134Y298230D03*
X600199Y290355D03*
X608069Y315945D03*
X596259Y308070D03*
X619884Y298230D03*
X615944Y290355D03*
X627754Y308070D03*
X623819Y315945D03*
X612009Y308070D03*
X635629Y298230D03*
X631694Y290355D03*
X643504Y308070D03*
X639569Y315945D03*
X651379Y298230D03*
X647439Y290355D03*
X659254Y308070D03*
X655314Y315945D03*
X667124Y298230D03*
X663189Y290355D03*
X674999Y308070D03*
X671064Y315945D03*
X682874Y298230D03*
X678939Y290355D03*
X690749Y308070D03*
X686809Y315945D03*
X698624Y298230D03*
X694684Y290355D03*
X706494Y308070D03*
X702559Y315945D03*
X726179Y290355D03*
X714369Y298230D03*
X710434Y290355D03*
X722244Y308070D03*
X718309Y315945D03*
X741929Y290355D03*
X730119Y298230D03*
X737994Y308070D03*
X734054Y315945D03*
X757679Y290355D03*
X745864Y298230D03*
X753739Y308070D03*
X749804Y315945D03*
X773424Y290355D03*
X761614Y298230D03*
X769489Y308070D03*
X765549Y315945D03*
X789174Y290355D03*
X777364Y298230D03*
X785234Y308070D03*
X781299Y315945D03*
X804919Y290355D03*
X793109Y298230D03*
X800984Y308070D03*
X797049Y315945D03*
X820669Y290355D03*
X808859Y298230D03*
X816734Y308070D03*
X812794Y315945D03*
X848229Y308070D03*
X860039Y290355D03*
Y315945D03*
G54D23*
X200000Y391500D03*
X216500D03*
G54D46*
X1367067Y60039D03*
Y96260D03*
X1392657Y60039D03*
Y96260D03*
G54D30*
X537994Y303150D03*
X825984D03*
G54D37*
X1008268Y244094D03*
Y411417D03*
X1227166Y155511D03*
X1227165Y411417D03*
G54D14*
X15000Y1008622D03*
X90119Y72219D03*
X227041Y1008622D03*
X653974Y1008621D03*
X955315Y850829D03*
X1157095Y128841D03*
X1385000Y1008622D03*
X1387875Y-15015D03*
G54D26*
X270078Y92125D03*
Y155117D03*
X490944Y79921D03*
Y255118D03*
X743897Y353543D03*
Y410629D03*
X1305117Y87548D03*
Y262745D03*
X1376968Y147243D03*
Y216535D03*
G54D38*
X1045000Y32598D03*
X1096732D03*
G54D35*
X600925Y44134D03*
X638917D03*
G54D27*
X332086Y408858D03*
X355708Y96456D03*
X450196Y257874D03*
X572243Y337992D03*
G54D16*
X25000Y980000D03*
X45000D03*
X55000Y975000D03*
X65000Y980000D03*
X75000Y975000D03*
X95000D03*
X206000Y982000D03*
X226000D03*
X246000D03*
X324500Y6000D03*
Y10500D03*
X1105000Y15000D03*
Y75000D03*
Y105000D03*
Y135000D03*
X1211500Y5500D03*
Y35500D03*
Y65500D03*
Y85500D03*
Y107500D03*
Y137500D03*
G54D20*
X140000Y720000D03*
Y740000D03*
X158500Y461500D03*
X182800Y465800D03*
X180000Y760000D03*
X220000D03*
X260000Y260000D03*
Y760000D03*
X378500Y812000D03*
Y824500D03*
X406500Y713500D03*
X412000Y724000D03*
X409500Y775500D03*
X422500Y764500D03*
X440000Y5000D03*
X431000Y713500D03*
Y724000D03*
X460000Y5000D03*
X477500Y715000D03*
X485000Y5000D03*
X491500Y715000D03*
X490500Y800000D03*
X504500Y715000D03*
X502500Y800000D03*
X515000Y5000D03*
X545000D03*
X560000Y20000D03*
X575000Y5000D03*
X604500Y714500D03*
X606000Y918500D03*
X616500Y714500D03*
X613500Y744500D03*
Y759000D03*
X620500Y848500D03*
X634000Y734500D03*
X633500Y749500D03*
X630500Y912000D03*
X650000Y110000D03*
X657500Y827000D03*
X656500Y906000D03*
X660000Y120000D03*
X685000Y5000D03*
X682500Y917500D03*
X695000Y20000D03*
X715000Y5000D03*
X725000Y20000D03*
X720000Y905000D03*
X728966Y53966D03*
Y65466D03*
X745000Y5000D03*
X755000Y20000D03*
X747800Y50200D03*
X762250Y71000D03*
X775000Y5000D03*
X785000Y20000D03*
X805000Y5000D03*
X800000Y100000D03*
X815000Y20000D03*
X810000Y120000D03*
X820500Y754000D03*
Y765500D03*
X835000Y5000D03*
X850000Y20000D03*
X865000Y5000D03*
X870000Y160000D03*
X880000Y20000D03*
X895000Y5000D03*
X890000Y140000D03*
X910000Y20000D03*
Y160000D03*
X915000Y805000D03*
Y825000D03*
Y845000D03*
Y865000D03*
Y885000D03*
Y905000D03*
Y925000D03*
Y945000D03*
Y965000D03*
X925000Y5000D03*
X955000D03*
X940000Y20000D03*
X970000D03*
X965000Y725500D03*
X985000Y5000D03*
X980000Y725500D03*
X1000000Y20000D03*
X1000500Y667500D03*
X990000D03*
X1015000Y5000D03*
X1045000D03*
X1060000Y20000D03*
X1075000Y5000D03*
X1090000Y20000D03*
X1100000Y180000D03*
X1091500Y846500D03*
X1105000Y5000D03*
Y400500D03*
X1235500Y5000D03*
X1268000D03*
X1307500D03*
X1305217Y612412D03*
X1305435Y603918D03*
X1337500Y5000D03*
X1354500Y703500D03*
X1379600Y584200D03*
X1377800Y603800D03*
X1378082Y614266D03*
X1381637Y611225D03*
X1381578Y607117D03*
X1394122Y5878D03*
X1387200Y584100D03*
X1384400Y598300D03*
Y601900D03*
G54D21*
X153937Y238898D03*
Y246772D03*
Y260551D03*
X224015Y234961D03*
Y246772D03*
Y260551D03*
G54D34*
X585315Y44134D03*
X654527D03*
G54D25*
X200118Y739409D03*
X190118D03*
X210118D03*
X230118Y729409D03*
Y739409D03*
X220118D03*
X250118D03*
X240118D03*
X260118Y729409D03*
Y739409D03*
X270118Y729409D03*
Y739409D03*
G54D11*
X19272Y337795D03*
Y396850D03*
X98838Y337795D03*
Y396850D03*
G54D40*
X1084646Y43267D03*
%LPC*%
G75*
G54D48*
G01X-245081Y-422119D02*
G02I-12000J0D01*
G01X-250231D02*
G02I-6850J0D01*
G01X-241081D02*
X-273081D01*
G01X-257081Y-438119D02*
Y-406119D01*
G01X-241081Y-438119D02*
Y-518119D01*
G01D02*
X1034819D01*
G01X-241081Y-473619D02*
X1034819D01*
G01X-241081Y-438119D02*
X1034819D01*
G01X247319D02*
Y-518119D01*
G01X384819Y-438119D02*
Y-518119D01*
G01X499819Y-438119D02*
Y-518119D01*
G01X667319Y-438119D02*
Y-518119D01*
G01X837319Y-438119D02*
Y-518119D01*
G01X1034819Y-438119D02*
Y-518119D01*
G01X1066819Y-422119D02*
X1034819D01*
G01X1050819Y-438119D02*
Y-406119D01*
G01X1062819Y-422119D02*
G02I-12000J0D01*
G01X1057669D02*
G02I-6850J0D01*
G54D49*
G01X-185516Y-508119D02*
Y-490619D01*
G01X-176346D02*
Y-508119D01*
G01Y-499369D02*
X-185516D01*
G01X-163431Y-508119D02*
X-165178Y-507827D01*
X-166706Y-506661D01*
X-168016Y-504911D01*
X-168890Y-502869D01*
X-169326Y-500536D01*
Y-498202D01*
X-168890Y-495869D01*
X-168016Y-493827D01*
X-166706Y-492078D01*
X-165178Y-490911D01*
X-163431Y-490619D01*
X-161685Y-490911D01*
X-160156Y-492078D01*
X-158846Y-493827D01*
X-157972Y-495869D01*
X-157536Y-498202D01*
Y-500536D01*
X-157972Y-502869D01*
X-158846Y-504911D01*
X-160156Y-506661D01*
X-161685Y-507827D01*
X-163431Y-508119D01*
G01X-150953D02*
Y-490619D01*
X-140909Y-508119D01*
Y-490619D01*
G01X-124064Y-508119D02*
X-132798D01*
Y-490619D01*
X-124064D01*
G01X-127558Y-499077D02*
X-132798D01*
G01X-110931Y-508119D02*
Y-500244D01*
X-115298Y-490619D01*
G01X-106564D02*
X-110931Y-500244D01*
G01X-74185Y-498786D02*
X-73311Y-497911D01*
X-72656Y-496453D01*
X-72219Y-494410D01*
X-72656Y-492661D01*
X-73529Y-491494D01*
X-75058Y-490619D01*
X-80953D01*
Y-508119D01*
X-73748D01*
X-72219Y-506953D01*
X-71346Y-505202D01*
X-70909Y-503161D01*
X-71346Y-501119D01*
X-72656Y-499369D01*
X-74185Y-498786D01*
X-80953D01*
G01X-63890Y-508119D02*
X-58431Y-490619D01*
X-52972Y-508119D01*
G01X-54938Y-501994D02*
X-61925D01*
G01X-45734Y-508119D02*
Y-490619D01*
X-41368D01*
X-39621Y-491494D01*
X-38311Y-492661D01*
X-37219Y-494410D01*
X-36346Y-496453D01*
X-36128Y-499369D01*
X-36346Y-502286D01*
X-37219Y-504328D01*
X-38311Y-506078D01*
X-39621Y-507244D01*
X-41368Y-508119D01*
X-45734D01*
G01X-22121Y-499369D02*
X-17754D01*
Y-504619D01*
X-19064Y-506369D01*
X-20593Y-507536D01*
X-22776Y-508119D01*
X-24959Y-507536D01*
X-26488Y-506369D01*
X-27798Y-504619D01*
X-28671Y-502577D01*
X-29108Y-500244D01*
Y-498202D01*
X-28671Y-496453D01*
X-27798Y-494410D01*
X-26488Y-492661D01*
X-25178Y-491494D01*
X-23431Y-490619D01*
X-21903D01*
X-20156Y-491202D01*
X-18846Y-492369D01*
G01X-1564Y-508119D02*
X-10298D01*
Y-490619D01*
X-1564D01*
G01X-5058Y-499077D02*
X-10298D01*
G01X7202Y-508119D02*
Y-490619D01*
X12661D01*
X14407Y-491494D01*
X15499Y-492661D01*
X15936Y-494994D01*
X15499Y-497328D01*
X14189Y-498786D01*
X12661Y-499661D01*
X7202D01*
G01X12661D02*
X15936Y-508119D01*
G01X48315Y-498786D02*
X49189Y-497911D01*
X49844Y-496453D01*
X50281Y-494410D01*
X49844Y-492661D01*
X48971Y-491494D01*
X47442Y-490619D01*
X41547D01*
Y-508119D01*
X48752D01*
X50281Y-506953D01*
X51154Y-505202D01*
X51591Y-503161D01*
X51154Y-501119D01*
X49844Y-499369D01*
X48315Y-498786D01*
X41547D01*
G01X58610Y-508119D02*
X64069Y-490619D01*
X69528Y-508119D01*
G01X67562Y-501994D02*
X60575D01*
G01X76984Y-505786D02*
X78731Y-507244D01*
X80696Y-508119D01*
X82442D01*
X84189Y-507244D01*
X85499Y-505786D01*
X86154Y-503744D01*
X85717Y-501703D01*
X84626Y-499952D01*
X82661Y-498786D01*
X80041Y-498202D01*
X78512Y-497036D01*
X77857Y-494994D01*
X78294Y-492952D01*
X79386Y-491494D01*
X80914Y-490619D01*
X82442D01*
X83971Y-491202D01*
X85281Y-492661D01*
G01X103436Y-508119D02*
X94702D01*
Y-490619D01*
X103436D01*
G01X99942Y-499077D02*
X94702D01*
G01X118315Y-498786D02*
X119189Y-497911D01*
X119844Y-496453D01*
X120281Y-494410D01*
X119844Y-492661D01*
X118971Y-491494D01*
X117442Y-490619D01*
X111547D01*
Y-508119D01*
X118752D01*
X120281Y-506953D01*
X121154Y-505202D01*
X121591Y-503161D01*
X121154Y-501119D01*
X119844Y-499369D01*
X118315Y-498786D01*
X111547D01*
G01X134069Y-508119D02*
X132322Y-507827D01*
X130794Y-506661D01*
X129484Y-504911D01*
X128610Y-502869D01*
X128174Y-500536D01*
Y-498202D01*
X128610Y-495869D01*
X129484Y-493827D01*
X130794Y-492078D01*
X132322Y-490911D01*
X134069Y-490619D01*
X135815Y-490911D01*
X137344Y-492078D01*
X138654Y-493827D01*
X139528Y-495869D01*
X139964Y-498202D01*
Y-500536D01*
X139528Y-502869D01*
X138654Y-504911D01*
X137344Y-506661D01*
X135815Y-507827D01*
X134069Y-508119D01*
G01X146110D02*
X151569Y-490619D01*
X157028Y-508119D01*
G01X155062Y-501994D02*
X148075D01*
G01X164702Y-508119D02*
Y-490619D01*
X170161D01*
X171907Y-491494D01*
X172999Y-492661D01*
X173436Y-494994D01*
X172999Y-497328D01*
X171689Y-498786D01*
X170161Y-499661D01*
X164702D01*
G01X170161D02*
X173436Y-508119D01*
G01X181766D02*
Y-490619D01*
X186132D01*
X187879Y-491494D01*
X189189Y-492661D01*
X190281Y-494410D01*
X191154Y-496453D01*
X191372Y-499369D01*
X191154Y-502286D01*
X190281Y-504328D01*
X189189Y-506078D01*
X187879Y-507244D01*
X186132Y-508119D01*
X181766D01*
G01X-37858Y-463119D02*
Y-445619D01*
X-32181Y-460202D01*
X-26504Y-445619D01*
Y-463119D01*
G01X-14681D02*
X-15991Y-462827D01*
X-17301Y-461661D01*
X-18175Y-459619D01*
X-18611Y-457286D01*
X-18175Y-454952D01*
X-17301Y-452911D01*
X-15991Y-451744D01*
X-14681Y-451453D01*
X-13371Y-451744D01*
X-12061Y-452911D01*
X-11188Y-454952D01*
X-10969Y-457286D01*
X-11188Y-459619D01*
X-12061Y-461661D01*
X-13371Y-462827D01*
X-14681Y-463119D01*
G01X6749Y-445619D02*
Y-463119D01*
G01Y-460495D02*
X5876Y-461953D01*
X4565Y-462827D01*
X3037Y-463119D01*
X1291Y-462536D01*
X-19Y-461078D01*
X-893Y-459328D01*
X-1111Y-457286D01*
X-893Y-455244D01*
X-19Y-453494D01*
X1291Y-452036D01*
X3037Y-451453D01*
X4565Y-451744D01*
X5657Y-452328D01*
X6749Y-453494D01*
G01X17044Y-455244D02*
X24031D01*
X23376Y-453202D01*
X22284Y-452036D01*
X20756Y-451453D01*
X19227Y-451744D01*
X17917Y-452619D01*
X17044Y-454661D01*
X16607Y-456411D01*
Y-458161D01*
X17044Y-459911D01*
X18136Y-461661D01*
X19446Y-462827D01*
X20974Y-463119D01*
X22502Y-462536D01*
X24031Y-460786D01*
G01X37819Y-463119D02*
Y-445619D01*
G01X281019Y-508119D02*
Y-490619D01*
X278399Y-494119D01*
G01Y-508119D02*
X283639D01*
G01X293716Y-504619D02*
X295025Y-506661D01*
X296772Y-507827D01*
X298737Y-508119D01*
X300484Y-507827D01*
X302231Y-506369D01*
X303322Y-504619D01*
X303541Y-502869D01*
X303104Y-500828D01*
X301576Y-499369D01*
X300047Y-498786D01*
X298082D01*
G01X300047D02*
X301357Y-497911D01*
X302449Y-496453D01*
X302886Y-494703D01*
X302449Y-492952D01*
X301357Y-491494D01*
X299392Y-490619D01*
X297427Y-490911D01*
X295462Y-492078D01*
G01X312307Y-506078D02*
X313836Y-507536D01*
X315582Y-508119D01*
X317329Y-507536D01*
X318857Y-505786D01*
X319949Y-503161D01*
X320386Y-500536D01*
Y-497328D01*
X319949Y-494703D01*
X318857Y-492369D01*
X317547Y-491202D01*
X316019Y-490619D01*
X314272Y-491202D01*
X312962Y-492369D01*
X312089Y-494119D01*
X311652Y-496453D01*
X312089Y-498494D01*
X313181Y-500536D01*
X314491Y-501703D01*
X316019Y-501994D01*
X317765Y-501411D01*
X319076Y-499952D01*
X320386Y-497328D01*
G01X336139Y-508119D02*
Y-490619D01*
X328060Y-503161D01*
X338978D01*
G01X351019Y-508119D02*
X352547Y-507827D01*
X354294Y-506953D01*
X355386Y-505495D01*
X355822Y-503452D01*
X355386Y-501411D01*
X354076Y-499661D01*
X352111Y-498786D01*
X349927D01*
X348617Y-498202D01*
X347525Y-496744D01*
X347089Y-494703D01*
X347744Y-492661D01*
X349272Y-491202D01*
X351019Y-490619D01*
X352765Y-491202D01*
X354294Y-492661D01*
X354949Y-494703D01*
X354512Y-496744D01*
X353421Y-498202D01*
X352111Y-498786D01*
X349927D01*
X347962Y-499661D01*
X346652Y-501411D01*
X346216Y-503452D01*
X346652Y-505495D01*
X347744Y-506953D01*
X349491Y-507827D01*
X351019Y-508119D01*
G01X267902Y-463119D02*
Y-445619D01*
X273142D01*
X274889Y-446494D01*
X276199Y-448536D01*
X276636Y-450869D01*
X276199Y-453202D01*
X275107Y-454952D01*
X273142Y-455828D01*
X267902D01*
G01X294572Y-447078D02*
X293262Y-446202D01*
X291734Y-445619D01*
X289987D01*
X288022Y-446494D01*
X286494Y-447952D01*
X285402Y-449703D01*
X284529Y-452619D01*
X284310Y-455244D01*
X284747Y-457869D01*
X285402Y-459619D01*
X286712Y-461369D01*
X288241Y-462536D01*
X289769Y-463119D01*
X291297D01*
X292826Y-462536D01*
X294136Y-461661D01*
X295228Y-460495D01*
G01X309015Y-453786D02*
X309889Y-452911D01*
X310544Y-451453D01*
X310981Y-449410D01*
X310544Y-447661D01*
X309671Y-446494D01*
X308142Y-445619D01*
X302247D01*
Y-463119D01*
X309452D01*
X310981Y-461953D01*
X311854Y-460202D01*
X312291Y-458161D01*
X311854Y-456119D01*
X310544Y-454369D01*
X309015Y-453786D01*
X302247D01*
G01X318219Y-468952D02*
X331319D01*
G01X337247Y-463119D02*
Y-445619D01*
X347291Y-463119D01*
Y-445619D01*
G01X359769Y-463119D02*
X358022Y-462827D01*
X356494Y-461661D01*
X355184Y-459911D01*
X354310Y-457869D01*
X353874Y-455536D01*
Y-453202D01*
X354310Y-450869D01*
X355184Y-448827D01*
X356494Y-447078D01*
X358022Y-445911D01*
X359769Y-445619D01*
X361515Y-445911D01*
X363044Y-447078D01*
X364354Y-448827D01*
X365228Y-450869D01*
X365664Y-453202D01*
Y-455536D01*
X365228Y-457869D01*
X364354Y-459911D01*
X363044Y-461661D01*
X361515Y-462827D01*
X359769Y-463119D01*
G01X410610Y-445619D02*
X416069Y-463119D01*
X421528Y-445619D01*
G01X437936Y-463119D02*
X429202D01*
Y-445619D01*
X437936D01*
G01X434442Y-454077D02*
X429202D01*
G01X446702Y-463119D02*
Y-445619D01*
X452161D01*
X453907Y-446494D01*
X454999Y-447661D01*
X455436Y-449994D01*
X454999Y-452328D01*
X453689Y-453786D01*
X452161Y-454661D01*
X446702D01*
G01X452161D02*
X455436Y-463119D01*
G01X468569Y-463702D02*
X468132Y-463411D01*
Y-462827D01*
X468569Y-462536D01*
X469006Y-462827D01*
Y-463411D01*
X468569Y-463702D01*
G01X433569Y-508119D02*
Y-490619D01*
X430949Y-494119D01*
G01Y-508119D02*
X436189D01*
G01X452815Y-498786D02*
X453689Y-497911D01*
X454344Y-496453D01*
X454781Y-494410D01*
X454344Y-492661D01*
X453471Y-491494D01*
X451942Y-490619D01*
X446047D01*
Y-508119D01*
X453252D01*
X454781Y-506953D01*
X455654Y-505202D01*
X456091Y-503161D01*
X455654Y-501119D01*
X454344Y-499369D01*
X452815Y-498786D01*
X446047D01*
G01X622886Y-490619D02*
Y-508119D01*
X614152D01*
G01X601456D02*
X601019Y-504328D01*
X600364Y-501119D01*
X599491Y-498202D01*
X598399Y-494994D01*
X596652Y-490619D01*
X605386D01*
G01X582209Y-499369D02*
X577842D01*
Y-504619D01*
X579152Y-506369D01*
X580681Y-507536D01*
X582864Y-508119D01*
X585047Y-507536D01*
X586576Y-506369D01*
X587886Y-504619D01*
X588759Y-502577D01*
X589196Y-500244D01*
Y-498202D01*
X588759Y-496453D01*
X587886Y-494410D01*
X586576Y-492661D01*
X585266Y-491494D01*
X583519Y-490619D01*
X581991D01*
X580244Y-491202D01*
X578934Y-492369D01*
G01X571041Y-508119D02*
Y-490619D01*
X560997Y-508119D01*
Y-490619D01*
G01X553322Y-508119D02*
Y-490619D01*
X548956D01*
X547209Y-491494D01*
X545899Y-492661D01*
X544807Y-494410D01*
X543934Y-496453D01*
X543716Y-499369D01*
X543934Y-502286D01*
X544807Y-504328D01*
X545899Y-506078D01*
X547209Y-507244D01*
X548956Y-508119D01*
X553322D01*
G01X544152Y-445619D02*
Y-463119D01*
X552886D01*
G01X569949D02*
Y-451453D01*
G01Y-453494D02*
X569076Y-452328D01*
X567765Y-451744D01*
X566237Y-451453D01*
X564709Y-452036D01*
X563399Y-453202D01*
X562525Y-454952D01*
X562089Y-457286D01*
X562525Y-459619D01*
X563399Y-461369D01*
X564709Y-462536D01*
X566237Y-463119D01*
X567765Y-462827D01*
X569076Y-461953D01*
X569949Y-460786D01*
G01X578934Y-468369D02*
X580244Y-468952D01*
X581991Y-468369D01*
X583082Y-467203D01*
X583956Y-465744D01*
X585265Y-461078D01*
X588104Y-451453D01*
G01X581117D02*
X585265Y-461078D01*
G01X597744Y-455244D02*
X604731D01*
X604076Y-453202D01*
X602984Y-452036D01*
X601456Y-451453D01*
X599927Y-451744D01*
X598617Y-452619D01*
X597744Y-454661D01*
X597307Y-456411D01*
Y-458161D01*
X597744Y-459911D01*
X598836Y-461661D01*
X600146Y-462827D01*
X601674Y-463119D01*
X603202Y-462536D01*
X604731Y-460786D01*
G01X615462Y-463119D02*
Y-451453D01*
G01Y-453786D02*
X616554Y-452619D01*
X617646Y-451744D01*
X619174Y-451453D01*
X620265Y-451744D01*
X621576Y-452619D01*
G01X686702Y-490619D02*
Y-508119D01*
X695436D01*
G01X703984Y-513369D02*
X705294Y-513952D01*
X707041Y-513369D01*
X708132Y-512203D01*
X709006Y-510744D01*
X710315Y-506078D01*
X713154Y-496453D01*
G01X706167D02*
X710315Y-506078D01*
G01X722357Y-508119D02*
Y-496453D01*
G01Y-499369D02*
X723231Y-497911D01*
X724541Y-496744D01*
X726287Y-496453D01*
X727815Y-496744D01*
X729126Y-497911D01*
X729781Y-499952D01*
Y-508119D01*
G01X739857D02*
Y-496453D01*
G01Y-499369D02*
X740731Y-497911D01*
X742041Y-496744D01*
X743787Y-496453D01*
X745315Y-496744D01*
X746626Y-497911D01*
X747281Y-499952D01*
Y-508119D01*
G01X774202Y-490619D02*
Y-508119D01*
X782936D01*
G01X796069Y-496453D02*
Y-508119D01*
G01Y-491786D02*
X795632Y-491494D01*
Y-490911D01*
X796069Y-490619D01*
X796506Y-490911D01*
Y-491494D01*
X796069Y-491786D01*
G01X809857Y-496453D02*
Y-504619D01*
X810731Y-506661D01*
X812041Y-507827D01*
X813569Y-508119D01*
X815097Y-507827D01*
X816407Y-506661D01*
X817281Y-504619D01*
G01Y-508119D02*
Y-496453D01*
G01X686266Y-463119D02*
Y-445619D01*
X690632D01*
X692379Y-446494D01*
X693689Y-447661D01*
X694781Y-449410D01*
X695654Y-451453D01*
X695872Y-454369D01*
X695654Y-457286D01*
X694781Y-459328D01*
X693689Y-461078D01*
X692379Y-462244D01*
X690632Y-463119D01*
X686266D01*
G01X705294Y-455244D02*
X712281D01*
X711626Y-453202D01*
X710534Y-452036D01*
X709006Y-451453D01*
X707477Y-451744D01*
X706167Y-452619D01*
X705294Y-454661D01*
X704857Y-456411D01*
Y-458161D01*
X705294Y-459911D01*
X706386Y-461661D01*
X707696Y-462827D01*
X709224Y-463119D01*
X710752Y-462536D01*
X712281Y-460786D01*
G01X722794Y-461078D02*
X723886Y-462244D01*
X725414Y-463119D01*
X726724D01*
X728034Y-462536D01*
X728907Y-461661D01*
X729344Y-460495D01*
X729126Y-458744D01*
X728252Y-457869D01*
X724322Y-456119D01*
X723449Y-454077D01*
X723886Y-452619D01*
X724759Y-451744D01*
X726069Y-451453D01*
X727379Y-451744D01*
X728689Y-452619D01*
G01X743569Y-451453D02*
Y-463119D01*
G01Y-446786D02*
X743132Y-446494D01*
Y-445911D01*
X743569Y-445619D01*
X744006Y-445911D01*
Y-446494D01*
X743569Y-446786D01*
G01X758012Y-467494D02*
X759541Y-468661D01*
X761287Y-468952D01*
X762815Y-468661D01*
X764126Y-467203D01*
X764999Y-465161D01*
Y-451453D01*
G01Y-453786D02*
X764126Y-452619D01*
X762815Y-451744D01*
X761287Y-451453D01*
X759541Y-452036D01*
X758449Y-453202D01*
X757575Y-455244D01*
X757139Y-457286D01*
X757357Y-459036D01*
X758231Y-461078D01*
X759541Y-462536D01*
X761287Y-463119D01*
X762597Y-462827D01*
X764126Y-461661D01*
X764999Y-460495D01*
G01X774857Y-463119D02*
Y-451453D01*
G01Y-454369D02*
X775731Y-452911D01*
X777041Y-451744D01*
X778787Y-451453D01*
X780315Y-451744D01*
X781626Y-452911D01*
X782281Y-454952D01*
Y-463119D01*
G01X792794Y-455244D02*
X799781D01*
X799126Y-453202D01*
X798034Y-452036D01*
X796506Y-451453D01*
X794977Y-451744D01*
X793667Y-452619D01*
X792794Y-454661D01*
X792357Y-456411D01*
Y-458161D01*
X792794Y-459911D01*
X793886Y-461661D01*
X795196Y-462827D01*
X796724Y-463119D01*
X798252Y-462536D01*
X799781Y-460786D01*
G01X810512Y-463119D02*
Y-451453D01*
G01Y-453786D02*
X811604Y-452619D01*
X812696Y-451744D01*
X814224Y-451453D01*
X815315Y-451744D01*
X816626Y-452619D01*
G01X857269Y-508119D02*
Y-490619D01*
X854649Y-494119D01*
G01Y-508119D02*
X859889D01*
G01X874769D02*
Y-490619D01*
X872149Y-494119D01*
G01Y-508119D02*
X877389D01*
G01X888339Y-508702D02*
X896199Y-490619D01*
G01X909769Y-508119D02*
Y-490619D01*
X907149Y-494119D01*
G01Y-508119D02*
X912389D01*
G01X922466Y-504619D02*
X923775Y-506661D01*
X925522Y-507827D01*
X927487Y-508119D01*
X929234Y-507827D01*
X930981Y-506369D01*
X932072Y-504619D01*
X932291Y-502869D01*
X931854Y-500828D01*
X930326Y-499369D01*
X928797Y-498786D01*
X926832D01*
G01X928797D02*
X930107Y-497911D01*
X931199Y-496453D01*
X931636Y-494703D01*
X931199Y-492952D01*
X930107Y-491494D01*
X928142Y-490619D01*
X926177Y-490911D01*
X924212Y-492078D01*
G01X940839Y-508702D02*
X948699Y-490619D01*
G01X958121Y-493536D02*
X959431Y-491786D01*
X960959Y-490911D01*
X962706Y-490619D01*
X964889Y-491202D01*
X966417Y-492661D01*
X966854Y-494410D01*
X966636Y-496161D01*
X965762Y-497619D01*
X961396Y-500536D01*
X959431Y-502577D01*
X958121Y-505495D01*
X957684Y-508119D01*
X966854D01*
G01X979769Y-490619D02*
X978022Y-491202D01*
X976712Y-492661D01*
X975839Y-494410D01*
X975184Y-496744D01*
X974966Y-499369D01*
X975184Y-501994D01*
X975839Y-504328D01*
X976712Y-506078D01*
X978022Y-507536D01*
X979769Y-508119D01*
X981515Y-507536D01*
X982826Y-506078D01*
X983699Y-504328D01*
X984354Y-501994D01*
X984572Y-499369D01*
X984354Y-496744D01*
X983699Y-494410D01*
X982826Y-492661D01*
X981515Y-491202D01*
X979769Y-490619D01*
G01X997269Y-508119D02*
Y-490619D01*
X994649Y-494119D01*
G01Y-508119D02*
X999889D01*
G01X1017389D02*
Y-490619D01*
X1009310Y-503161D01*
X1020228D01*
G01X904966Y-463119D02*
Y-445619D01*
X909332D01*
X911079Y-446494D01*
X912389Y-447661D01*
X913481Y-449410D01*
X914354Y-451453D01*
X914572Y-454369D01*
X914354Y-457286D01*
X913481Y-459328D01*
X912389Y-461078D01*
X911079Y-462244D01*
X909332Y-463119D01*
X904966D01*
G01X931199D02*
Y-451453D01*
G01Y-453494D02*
X930326Y-452328D01*
X929015Y-451744D01*
X927487Y-451453D01*
X925959Y-452036D01*
X924649Y-453202D01*
X923775Y-454952D01*
X923339Y-457286D01*
X923775Y-459619D01*
X924649Y-461369D01*
X925959Y-462536D01*
X927487Y-463119D01*
X929015Y-462827D01*
X930326Y-461953D01*
X931199Y-460786D01*
G01X944769Y-445619D02*
Y-463119D01*
G01X941712Y-451453D02*
X947826D01*
G01X958994Y-455244D02*
X965981D01*
X965326Y-453202D01*
X964234Y-452036D01*
X962706Y-451453D01*
X961177Y-451744D01*
X959867Y-452619D01*
X958994Y-454661D01*
X958557Y-456411D01*
Y-458161D01*
X958994Y-459911D01*
X960086Y-461661D01*
X961396Y-462827D01*
X962924Y-463119D01*
X964452Y-462536D01*
X965981Y-460786D01*
M02*
